G04 ================== begin FILE IDENTIFICATION RECORD ==================*
G04 Layout Name:  D:/<user>/Wistron_project/16315-1/gbr/16315-1.brd*
G04 Film Name:    DP_REF_L12*
G04 File Format:  Gerber RS274X*
G04 File Origin:  Cadence Allegro 16.5-S056*
G04 Origin Date:  Fri Jun 09 15:33:16 2017*
G04 *
G04 Layer:  BOARD GEOMETRY/DP_REF_L12_TBL*
G04 Layer:  BOARD GEOMETRY/DP_REF_L12_BOTTOM*
G04 Layer:  BOARD GEOMETRY/PANEL_OUTLINE*
G04 *
G04 Offset:    (0.00 0.00)*
G04 Mirror:    No*
G04 Mode:      Positive*
G04 Rotation:  0*
G04 FullContactRelief:  No*
G04 UndefLineWidth:     6.00*
G04 ================== end FILE IDENTIFICATION RECORD ====================*
%FSLAX35Y35*MOIN*%
%IR0*IPPOS*OFA0.00000B0.00000*MIA0B0*SFA1.00000B1.00000*%
%ADD10C,.02*%
%ADD11C,.005*%
%ADD12C,.006*%
%ADD13C,.0065*%
G75*
%LPD*%
G75*
G54D10*
G01X1985143Y1554618D02*
X2737643D01*
G01X1985143Y1519968D02*
X2737643D01*
G01X1985143Y1623918D02*
Y1519968D01*
G01Y1589268D02*
X2737643D01*
G01X1985143Y1623918D02*
X2737643D01*
G01X2160143D02*
Y1519968D01*
G01X2422643Y1623918D02*
Y1519968D01*
G01X2527643Y1623918D02*
Y1519968D01*
G01X2737643Y1623918D02*
Y1519968D01*
G54D11*
G01X1075245Y1227004D02*
X1099722D01*
G01X1072425Y1229824D02*
G03X1075245Y1227004I2820J0D01*
G01X1073575Y1208564D02*
Y1209149D01*
G01X1072425D02*
Y1208564D01*
G01X1075245Y1206894D02*
G02X1073575Y1208564I0J1670D01*
G01X1072425D02*
G03X1075245Y1205744I2820J0D01*
G01X1095784Y1206894D02*
X1075245D01*
G01Y1205744D02*
X1095785D01*
G01X1075245D02*
X1095785D01*
G01X1095784Y1206894D02*
X1075245D01*
G01X1072425Y1208564D02*
G03X1075245Y1205744I2820J0D01*
G01Y1206894D02*
G02X1073575Y1208564I0J1670D01*
G01X1072425Y1209149D02*
Y1208564D01*
G01X1073575D02*
Y1209149D01*
G01X1075245Y1213981D02*
X1099721D01*
G01X1075245Y1212831D02*
X1099722D01*
G01X1073575Y1215651D02*
G03X1075245Y1213981I1670J0D01*
G01X1072425Y1215651D02*
G03X1075245Y1212831I2820J0D01*
G01X1073575Y1216236D02*
Y1215651D01*
G01X1072425Y1216236D02*
Y1215651D01*
G01X1075245Y1212831D02*
X1099722D01*
G01X1075245Y1213981D02*
X1099721D01*
G01X1072425Y1215651D02*
G03X1075245Y1212831I2820J0D01*
G01X1073575Y1215651D02*
G03X1075245Y1213981I1670J0D01*
G01X1072425Y1216236D02*
Y1215651D01*
G01X1073575Y1216236D02*
Y1215651D01*
G01Y1222737D02*
Y1223322D01*
G01X1072425D02*
Y1222737D01*
G01X1075245Y1221067D02*
G02X1073575Y1222737I0J1670D01*
G01X1072425D02*
G03X1075245Y1219917I2820J0D01*
G01X1095784Y1221067D02*
X1075245D01*
G01Y1219917D02*
X1095785D01*
G01X1075245D02*
X1095785D01*
G01X1095784Y1221067D02*
X1075245D01*
G01X1072425Y1222737D02*
G03X1075245Y1219917I2820J0D01*
G01Y1221067D02*
G02X1073575Y1222737I0J1670D01*
G01X1072425Y1223322D02*
Y1222737D01*
G01X1073575D02*
Y1223322D01*
G01X1075245Y1227004D02*
X1099722D01*
G01X1072425Y1229824D02*
G03X1075245Y1227004I2820J0D01*
G01Y1228154D02*
X1099721D01*
G01X1073575Y1229824D02*
G03X1075245Y1228154I1670J0D01*
G01X1073575Y1230409D02*
Y1229824D01*
G01X1072425Y1230409D02*
Y1229824D01*
G01X1073575Y1236911D02*
Y1237496D01*
G01X1072425D02*
Y1236911D01*
G01X1075245Y1235241D02*
G02X1073575Y1236911I0J1670D01*
G01X1072425D02*
G03X1075245Y1234091I2820J0D01*
G01X1095783Y1235241D02*
X1075245D01*
G01X1077597Y1234090D02*
X1095785D01*
G01X1075245Y1234091D02*
X1077596D01*
G01X1077597Y1234090D02*
X1095785D01*
G01X1095783Y1235241D02*
X1075245D01*
G01Y1234091D02*
X1077596D01*
G01X1095783Y1235241D02*
X1075245D01*
G01X1072425Y1236911D02*
G03X1075245Y1234091I2820J0D01*
G01Y1235241D02*
G02X1073575Y1236911I0J1670D01*
G01X1072425Y1237496D02*
Y1236911D01*
G01X1073575D02*
Y1237496D01*
G01X1075245Y1242327D02*
X1099721D01*
G01X1075245Y1241177D02*
X1099722D01*
G01X1073575Y1243997D02*
G03X1075245Y1242327I1670J0D01*
G01X1072425Y1243997D02*
G03X1075245Y1241177I2820J0D01*
G01X1073575Y1244582D02*
Y1243997D01*
G01X1072425Y1244582D02*
Y1243997D01*
G01X1075245Y1241177D02*
X1099722D01*
G01X1075245Y1242327D02*
X1099721D01*
G01X1072425Y1243997D02*
G03X1075245Y1241177I2820J0D01*
G01X1073575Y1243997D02*
G03X1075245Y1242327I1670J0D01*
G01X1072425Y1244582D02*
Y1243997D01*
G01X1073575Y1244582D02*
Y1243997D01*
G01X1075245Y1228154D02*
X1099721D01*
G01X1073575Y1229824D02*
G03X1075245Y1228154I1670J0D01*
G01X1072425Y1230409D02*
Y1229824D01*
G01X1073575Y1230409D02*
Y1229824D01*
G01Y1293604D02*
Y1294189D01*
G01X1072425D02*
Y1293604D01*
G01X1075245Y1291934D02*
G02X1073575Y1293604I0J1670D01*
G01X1072425D02*
G03X1075245Y1290784I2820J0D01*
G01X1095784Y1291934D02*
X1075245D01*
G01Y1290784D02*
X1095785D01*
G01X1075245D02*
X1095785D01*
G01X1095784Y1291934D02*
X1075245D01*
G01X1072425Y1293604D02*
G03X1075245Y1290784I2820J0D01*
G01Y1291934D02*
G02X1073575Y1293604I0J1670D01*
G01X1072425Y1294189D02*
Y1293604D01*
G01X1073575D02*
Y1294189D01*
G01X1075245Y1299020D02*
X1099721D01*
G01X1075245Y1297870D02*
X1099722D01*
G01X1073575Y1300690D02*
G03X1075245Y1299020I1670J0D01*
G01X1072425Y1300690D02*
G03X1075245Y1297870I2820J0D01*
G01X1073575Y1301275D02*
Y1300690D01*
G01X1072425Y1301275D02*
Y1300690D01*
G01X1075245Y1297870D02*
X1099722D01*
G01X1075245Y1299020D02*
X1099721D01*
G01X1072425Y1300690D02*
G03X1075245Y1297870I2820J0D01*
G01X1073575Y1300690D02*
G03X1075245Y1299020I1670J0D01*
G01X1072425Y1301275D02*
Y1300690D01*
G01X1073575Y1301275D02*
Y1300690D01*
G01Y1307777D02*
Y1308362D01*
G01X1072425D02*
Y1307777D01*
G01X1075245Y1306107D02*
G02X1073575Y1307777I0J1670D01*
G01X1072425D02*
G03X1075245Y1304957I2820J0D01*
G01X1095784Y1306107D02*
X1075245D01*
G01Y1304957D02*
X1095785D01*
G01X1075245D02*
X1095785D01*
G01X1095784Y1306107D02*
X1075245D01*
G01X1072425Y1307777D02*
G03X1075245Y1304957I2820J0D01*
G01Y1306107D02*
G02X1073575Y1307777I0J1670D01*
G01X1072425Y1308362D02*
Y1307777D01*
G01X1073575D02*
Y1308362D01*
G01X1075245Y1313193D02*
X1099721D01*
G01X1075245Y1312043D02*
X1099722D01*
G01X1073575Y1314863D02*
G03X1075245Y1313193I1670J0D01*
G01X1072425Y1314863D02*
G03X1075245Y1312043I2820J0D01*
G01X1073575Y1315448D02*
Y1314863D01*
G01X1072425Y1315448D02*
Y1314863D01*
G01X1075245Y1312043D02*
X1099722D01*
G01X1075245Y1313193D02*
X1099721D01*
G01X1072425Y1314863D02*
G03X1075245Y1312043I2820J0D01*
G01X1073575Y1314863D02*
G03X1075245Y1313193I1670J0D01*
G01X1072425Y1315448D02*
Y1314863D01*
G01X1073575Y1315448D02*
Y1314863D01*
G01Y1321950D02*
Y1322535D01*
G01X1072425D02*
Y1321950D01*
G01X1075245Y1320280D02*
G02X1073575Y1321950I0J1670D01*
G01X1072425D02*
G03X1075245Y1319130I2820J0D01*
G01X1095784Y1320280D02*
X1075245D01*
G01Y1319130D02*
X1095785D01*
G01X1075245D02*
X1095785D01*
G01X1095784Y1320280D02*
X1075245D01*
G01X1072425Y1321950D02*
G03X1075245Y1319130I2820J0D01*
G01Y1320280D02*
G02X1073575Y1321950I0J1670D01*
G01X1072425Y1322535D02*
Y1321950D01*
G01X1073575D02*
Y1322535D01*
G01X1075245Y1327367D02*
X1099721D01*
G01X1075245Y1326217D02*
X1099722D01*
G01X1073575Y1329037D02*
G03X1075245Y1327367I1670J0D01*
G01X1072425Y1329037D02*
G03X1075245Y1326217I2820J0D01*
G01X1073575Y1329622D02*
Y1329037D01*
G01X1072425Y1329622D02*
Y1329037D01*
G01X1075245Y1326217D02*
X1099722D01*
G01X1075245Y1327367D02*
X1099721D01*
G01X1072425Y1329037D02*
G03X1075245Y1326217I2820J0D01*
G01X1073575Y1329037D02*
G03X1075245Y1327367I1670J0D01*
G01X1072425Y1329622D02*
Y1329037D01*
G01X1073575Y1329622D02*
Y1329037D01*
G01Y1378643D02*
Y1379228D01*
G01X1072425D02*
Y1378643D01*
G01X1075245Y1376973D02*
G02X1073575Y1378643I0J1670D01*
G01X1072425D02*
G03X1075245Y1375823I2820J0D01*
G01X1095784Y1376973D02*
X1075245D01*
G01Y1375823D02*
X1095785D01*
G01X1075245D02*
X1095785D01*
G01X1095784Y1376973D02*
X1075245D01*
G01X1072425Y1378643D02*
G03X1075245Y1375823I2820J0D01*
G01Y1376973D02*
G02X1073575Y1378643I0J1670D01*
G01X1072425Y1379228D02*
Y1378643D01*
G01X1073575D02*
Y1379228D01*
G01X1075245Y1384060D02*
X1099721D01*
G01X1075245Y1382910D02*
X1099722D01*
G01X1073575Y1385730D02*
G03X1075245Y1384060I1670J0D01*
G01X1072425Y1385730D02*
G03X1075245Y1382910I2820J0D01*
G01X1073575Y1386315D02*
Y1385730D01*
G01X1072425Y1386315D02*
Y1385730D01*
G01X1075245Y1382910D02*
X1099722D01*
G01X1075245Y1384060D02*
X1099721D01*
G01X1072425Y1385730D02*
G03X1075245Y1382910I2820J0D01*
G01X1073575Y1385730D02*
G03X1075245Y1384060I1670J0D01*
G01X1072425Y1386315D02*
Y1385730D01*
G01X1073575Y1386315D02*
Y1385730D01*
G01Y1392816D02*
Y1393401D01*
G01X1072425D02*
Y1392816D01*
G01X1075245Y1391146D02*
G02X1073575Y1392816I0J1670D01*
G01X1072425D02*
G03X1075245Y1389996I2820J0D01*
G01X1095784Y1391146D02*
X1075245D01*
G01Y1389996D02*
X1095785D01*
G01X1075245D02*
X1095785D01*
G01X1095784Y1391146D02*
X1075245D01*
G01X1072425Y1392816D02*
G03X1075245Y1389996I2820J0D01*
G01Y1391146D02*
G02X1073575Y1392816I0J1670D01*
G01X1072425Y1393401D02*
Y1392816D01*
G01X1073575D02*
Y1393401D01*
G01X1075245Y1398233D02*
X1099721D01*
G01X1075245Y1397083D02*
X1099722D01*
G01X1073575Y1399903D02*
G03X1075245Y1398233I1670J0D01*
G01X1072425Y1399903D02*
G03X1075245Y1397083I2820J0D01*
G01X1073575Y1400488D02*
Y1399903D01*
G01X1072425Y1400488D02*
Y1399903D01*
G01X1075245Y1397083D02*
X1099722D01*
G01X1075245Y1398233D02*
X1099721D01*
G01X1072425Y1399903D02*
G03X1075245Y1397083I2820J0D01*
G01X1073575Y1399903D02*
G03X1075245Y1398233I1670J0D01*
G01X1072425Y1400488D02*
Y1399903D01*
G01X1073575Y1400488D02*
Y1399903D01*
G01Y1406989D02*
Y1407574D01*
G01X1072425D02*
Y1406989D01*
G01X1075245Y1405319D02*
G02X1073575Y1406989I0J1670D01*
G01X1072425D02*
G03X1075245Y1404169I2820J0D01*
G01X1095784Y1405319D02*
X1075245D01*
G01Y1404169D02*
X1095785D01*
G01X1075245D02*
X1095785D01*
G01X1095784Y1405319D02*
X1075245D01*
G01X1072425Y1406989D02*
G03X1075245Y1404169I2820J0D01*
G01Y1405319D02*
G02X1073575Y1406989I0J1670D01*
G01X1072425Y1407574D02*
Y1406989D01*
G01X1073575D02*
Y1407574D01*
G01X1075245Y1412406D02*
X1099721D01*
G01X1075245Y1411256D02*
X1099722D01*
G01X1073575Y1414076D02*
G03X1075245Y1412406I1670J0D01*
G01X1072425Y1414076D02*
G03X1075245Y1411256I2820J0D01*
G01X1073575Y1414661D02*
Y1414076D01*
G01X1072425Y1414661D02*
Y1414076D01*
G01X1075245Y1411256D02*
X1099722D01*
G01X1075245Y1412406D02*
X1099721D01*
G01X1072425Y1414076D02*
G03X1075245Y1411256I2820J0D01*
G01X1073575Y1414076D02*
G03X1075245Y1412406I1670J0D01*
G01X1072425Y1414661D02*
Y1414076D01*
G01X1073575Y1414661D02*
Y1414076D01*
G01X1125947Y1175916D02*
Y1174930D01*
G01X1127097Y1175916D02*
Y1174930D01*
G01X1126648Y1177610D02*
G03X1125947Y1175916I1695J-1693D01*
G01X1127462Y1176797D02*
G03X1127097Y1175916I881J-881D01*
G01X1128913Y1178548D02*
G03X1126648Y1177610I0J-3203D01*
G01X1128913Y1177398D02*
G03X1127462Y1176797I0J-2052D01*
G01X1133723Y1178548D02*
X1128913D01*
G01X1133597Y1177398D02*
X1128913D01*
G01X1136168Y1178008D02*
X1133723Y1178548D01*
G01X1135721Y1176929D02*
X1133597Y1177398D01*
G01X1148537Y1170125D02*
X1136168Y1178008D01*
G01X1147704Y1169292D02*
X1135721Y1176929D01*
G01X1127097Y1175916D02*
Y1174930D01*
G01X1125947Y1175916D02*
Y1174930D01*
G01X1127462Y1176797D02*
G03X1127097Y1175916I881J-881D01*
G01X1126648Y1177610D02*
G03X1125947Y1175916I1695J-1693D01*
G01X1128913Y1177398D02*
G03X1127462Y1176797I0J-2052D01*
G01X1128913Y1178548D02*
G03X1126648Y1177610I0J-3203D01*
G01X1133597Y1177398D02*
X1128913D01*
G01X1133723Y1178548D02*
X1128913D01*
G01X1135721Y1176929D02*
X1133597Y1177398D01*
G01X1136168Y1178008D02*
X1133723Y1178548D01*
G01X1147704Y1169292D02*
X1135721Y1176929D01*
G01X1148537Y1170125D02*
X1136168Y1178008D01*
G01X1148537Y1170125D02*
X1136168Y1178008D01*
G01X1135051Y1199808D02*
X1141715Y1198331D01*
G01X1141270Y1197251D02*
X1134925Y1198658D01*
G01X1132850Y1199808D02*
X1135051D01*
G01X1134925Y1198658D02*
X1132850D01*
G01X1130585Y1198870D02*
G02X1132850Y1199808I2265J-2265D01*
G01Y1198658D02*
G03X1131399Y1198057I0J-2052D01*
G01X1129884Y1197176D02*
G02X1130585Y1198870I2396J1D01*
G01X1131399Y1198057D02*
G03X1131034Y1197176I881J-881D01*
G01X1129884Y1196190D02*
Y1197176D01*
G01X1131034D02*
Y1196190D01*
G01Y1197176D02*
Y1196190D01*
G01X1129884D02*
Y1197176D01*
G01X1131399Y1198057D02*
G03X1131034Y1197176I881J-881D01*
G01X1129884D02*
G02X1130585Y1198870I2396J1D01*
G01X1132850Y1198658D02*
G03X1131399Y1198057I0J-2052D01*
G01X1130585Y1198870D02*
G02X1132850Y1199808I2265J-2265D01*
G01X1134925Y1198658D02*
X1132850D01*
G01Y1199808D02*
X1135051D01*
G01X1141270Y1197251D02*
X1134925Y1198658D01*
G01X1135051Y1199808D02*
X1141715Y1198331D01*
G01X1134226Y1192721D02*
X1141460Y1191115D01*
G01X1134099Y1191571D02*
X1141013Y1190036D01*
G01X1128913Y1192721D02*
X1134226D01*
G01X1128913Y1191571D02*
X1134099D01*
G01X1126648Y1191783D02*
G02X1128913Y1192721I2265J-2265D01*
G01X1127462Y1190970D02*
G02X1128913Y1191571I1451J-1451D01*
G01X1125947Y1190089D02*
G02X1126648Y1191783I2396J1D01*
G01X1127097Y1190089D02*
G02X1127462Y1190970I1246J0D01*
G01X1125947Y1189103D02*
Y1190089D01*
G01X1127097Y1189103D02*
Y1190089D01*
G01X1134099Y1191571D02*
X1141013Y1190036D01*
G01X1134226Y1192721D02*
X1141460Y1191115D01*
G01X1128913Y1191571D02*
X1134099D01*
G01X1128913Y1192721D02*
X1134226D01*
G01X1127462Y1190970D02*
G02X1128913Y1191571I1451J-1451D01*
G01X1126648Y1191783D02*
G02X1128913Y1192721I2265J-2265D01*
G01X1127097Y1190089D02*
G02X1127462Y1190970I1246J0D01*
G01X1125947Y1190089D02*
G02X1126648Y1191783I2396J1D01*
G01X1127097Y1189103D02*
Y1190089D01*
G01X1125947Y1189103D02*
Y1190089D01*
G01X1132850Y1185634D02*
X1136394D01*
G01X1136268Y1184484D02*
X1132850D01*
G01X1130585Y1184696D02*
G02X1132850Y1185634I2265J-2265D01*
G01Y1184484D02*
G03X1131399Y1183883I0J-2052D01*
G01X1129884Y1183002D02*
G02X1130585Y1184696I2396J1D01*
G01X1131399Y1183883D02*
G03X1131034Y1183002I881J-881D01*
G01X1129884Y1182016D02*
Y1183002D01*
G01X1131034D02*
Y1182016D01*
G01Y1183002D02*
Y1182016D01*
G01X1129884D02*
Y1183002D01*
G01X1131399Y1183883D02*
G03X1131034Y1183002I881J-881D01*
G01X1129884D02*
G02X1130585Y1184696I2396J1D01*
G01X1132850Y1184484D02*
G03X1131399Y1183883I0J-2052D01*
G01X1130585Y1184696D02*
G02X1132850Y1185634I2265J-2265D01*
G01X1136268Y1184484D02*
X1132850D01*
G01Y1185634D02*
X1136394D01*
G01X1102688Y1225524D02*
Y1224536D01*
G01X1101538Y1225522D02*
Y1224536D01*
G01X1102164Y1227019D02*
G02X1102688Y1225524I-1871J-1495D01*
G01X1101265Y1226300D02*
G02X1101538Y1225522I-972J-778D01*
G01X1101173Y1226403D02*
G02X1101265Y1226300I-882J-880D01*
G01X1101987Y1227217D02*
G02X1102164Y1227019I-1695J-1694D01*
G01X1101265Y1226300D02*
G02X1101538Y1225522I-972J-778D01*
G01X1101173Y1226403D02*
G02X1101265Y1226300I-882J-880D01*
G01X1099721Y1228154D02*
G02X1101987Y1227217I2J-3203D01*
G01X1099722Y1227004D02*
G02X1101173Y1226403I0J-2052D01*
G01X1098050Y1205957D02*
G03X1095784Y1206894I-2264J-2266D01*
G01X1095785Y1205744D02*
G02X1097236Y1205143I0J-2052D01*
G01X1098227Y1205759D02*
G03X1098050Y1205957I-1872J-1496D01*
G01X1097328Y1205040D02*
G02X1097601Y1204262I-972J-778D01*
G01X1097236Y1205143D02*
G02X1097328Y1205040I-882J-880D01*
G01X1098751Y1204264D02*
G03X1098227Y1205759I-2395J0D01*
G01X1097328Y1205040D02*
G02X1097601Y1204262I-972J-778D01*
G01X1097236Y1205143D02*
G02X1097328Y1205040I-882J-880D01*
G01X1098751Y1203276D02*
Y1204264D01*
G01X1097601Y1204262D02*
Y1203276D01*
G01Y1204262D02*
Y1203276D01*
G01X1098751D02*
Y1204264D01*
G01X1097328Y1205040D02*
G02X1097601Y1204262I-972J-778D01*
G01X1098227Y1205759D02*
G03X1098050Y1205957I-1872J-1496D01*
G01X1098751Y1204264D02*
G03X1098227Y1205759I-2395J0D01*
G01X1097236Y1205143D02*
G02X1097328Y1205040I-882J-880D01*
G01X1098227Y1205759D02*
G03X1098050Y1205957I-1872J-1496D01*
G01X1098751Y1204264D02*
G03X1098227Y1205759I-2395J0D01*
G01X1095785Y1205744D02*
G02X1097236Y1205143I0J-2052D01*
G01X1098050Y1205957D02*
G03X1095784Y1206894I-2264J-2266D01*
G01X1102688Y1211351D02*
Y1210363D01*
G01X1101538Y1211349D02*
Y1210363D01*
G01X1102164Y1212846D02*
G02X1102688Y1211351I-1871J-1495D01*
G01X1101265Y1212127D02*
G02X1101538Y1211349I-972J-778D01*
G01X1101173Y1212230D02*
G02X1101265Y1212127I-882J-880D01*
G01X1101987Y1213044D02*
G02X1102164Y1212846I-1695J-1694D01*
G01X1101265Y1212127D02*
G02X1101538Y1211349I-972J-778D01*
G01X1101173Y1212230D02*
G02X1101265Y1212127I-882J-880D01*
G01X1099721Y1213981D02*
G02X1101987Y1213044I2J-3203D01*
G01X1099722Y1212831D02*
G02X1101173Y1212230I0J-2052D01*
G01X1101538Y1211349D02*
Y1210363D01*
G01X1102688Y1211351D02*
Y1210363D01*
G01X1101265Y1212127D02*
G02X1101538Y1211349I-972J-778D01*
G01X1102164Y1212846D02*
G02X1102688Y1211351I-1871J-1495D01*
G01X1101987Y1213044D02*
G02X1102164Y1212846I-1695J-1694D01*
G01X1101173Y1212230D02*
G02X1101265Y1212127I-882J-880D01*
G01X1102164Y1212846D02*
G02X1102688Y1211351I-1871J-1495D01*
G01X1101987Y1213044D02*
G02X1102164Y1212846I-1695J-1694D01*
G01X1099722Y1212831D02*
G02X1101173Y1212230I0J-2052D01*
G01X1099721Y1213981D02*
G02X1101987Y1213044I2J-3203D01*
G01X1098050Y1220130D02*
G03X1095784Y1221067I-2264J-2266D01*
G01X1095785Y1219917D02*
G02X1097236Y1219316I0J-2052D01*
G01X1098227Y1219932D02*
G03X1098050Y1220130I-1872J-1496D01*
G01X1097328Y1219213D02*
G02X1097601Y1218435I-972J-778D01*
G01X1097236Y1219316D02*
G02X1097328Y1219213I-882J-880D01*
G01X1098751Y1218437D02*
G03X1098227Y1219932I-2395J0D01*
G01X1097328Y1219213D02*
G02X1097601Y1218435I-972J-778D01*
G01X1097236Y1219316D02*
G02X1097328Y1219213I-882J-880D01*
G01X1098751Y1217449D02*
Y1218437D01*
G01X1097601Y1218435D02*
Y1217449D01*
G01Y1218435D02*
Y1217449D01*
G01X1098751D02*
Y1218437D01*
G01X1097328Y1219213D02*
G02X1097601Y1218435I-972J-778D01*
G01X1098227Y1219932D02*
G03X1098050Y1220130I-1872J-1496D01*
G01X1098751Y1218437D02*
G03X1098227Y1219932I-2395J0D01*
G01X1097236Y1219316D02*
G02X1097328Y1219213I-882J-880D01*
G01X1098227Y1219932D02*
G03X1098050Y1220130I-1872J-1496D01*
G01X1098751Y1218437D02*
G03X1098227Y1219932I-2395J0D01*
G01X1095785Y1219917D02*
G02X1097236Y1219316I0J-2052D01*
G01X1098050Y1220130D02*
G03X1095784Y1221067I-2264J-2266D01*
G01X1101538Y1225522D02*
Y1224536D01*
G01X1102688Y1225524D02*
Y1224536D01*
G01X1101265Y1226300D02*
G02X1101538Y1225522I-972J-778D01*
G01X1102164Y1227019D02*
G02X1102688Y1225524I-1871J-1495D01*
G01X1101987Y1227217D02*
G02X1102164Y1227019I-1695J-1694D01*
G01X1101173Y1226403D02*
G02X1101265Y1226300I-882J-880D01*
G01X1102164Y1227019D02*
G02X1102688Y1225524I-1871J-1495D01*
G01X1101987Y1227217D02*
G02X1102164Y1227019I-1695J-1694D01*
G01X1099722Y1227004D02*
G02X1101173Y1226403I0J-2052D01*
G01X1099721Y1228154D02*
G02X1101987Y1227217I2J-3203D01*
G01X1132270Y1276610D02*
X1145998Y1273573D01*
G01X1127462Y1276009D02*
G02X1128913Y1276610I1451J-1451D01*
G01X1125947Y1275128D02*
G02X1126648Y1276822I2396J1D01*
G01X1127097Y1275128D02*
G02X1127462Y1276009I1246J0D01*
G01X1125947Y1274142D02*
Y1275128D01*
G01X1127097Y1274142D02*
Y1275128D01*
G01X1132270Y1276610D02*
X1145998Y1273573D01*
G01X1127462Y1276009D02*
G02X1128913Y1276610I1451J-1451D01*
G01X1127097Y1275128D02*
G02X1127462Y1276009I1246J0D01*
G01X1125947Y1275128D02*
G02X1126648Y1276822I2396J1D01*
G01X1127097Y1274142D02*
Y1275128D01*
G01X1125947Y1274142D02*
Y1275128D01*
G01X1129884Y1268042D02*
Y1267056D01*
G01X1131034Y1268042D02*
Y1267056D01*
G01X1130585Y1269736D02*
G03X1129884Y1268042I1695J-1693D01*
G01X1131399Y1268923D02*
G03X1131034Y1268042I881J-881D01*
G01X1132850Y1270674D02*
G03X1130585Y1269736I0J-3203D01*
G01X1132850Y1269524D02*
G03X1131399Y1268923I0J-2052D01*
G01X1135479Y1270674D02*
X1132850D01*
G01X1135353Y1269524D02*
X1132850D01*
G01X1144468Y1268681D02*
X1135479Y1270674D01*
G01X1144021Y1267602D02*
X1135353Y1269524D01*
G01X1131034Y1268042D02*
Y1267056D01*
G01X1129884Y1268042D02*
Y1267056D01*
G01X1131399Y1268923D02*
G03X1131034Y1268042I881J-881D01*
G01X1130585Y1269736D02*
G03X1129884Y1268042I1695J-1693D01*
G01X1132850Y1269524D02*
G03X1131399Y1268923I0J-2052D01*
G01X1132850Y1270674D02*
G03X1130585Y1269736I0J-3203D01*
G01X1135353Y1269524D02*
X1132850D01*
G01X1135479Y1270674D02*
X1132850D01*
G01X1144021Y1267602D02*
X1135353Y1269524D01*
G01X1144468Y1268681D02*
X1135479Y1270674D01*
G01X1125947Y1260955D02*
Y1259969D01*
G01X1127097D02*
Y1260955D01*
G01X1126648Y1262649D02*
G03X1125947Y1260955I1695J-1693D01*
G01X1127097D02*
G02X1127462Y1261836I1246J0D01*
G01X1128913Y1263587D02*
G03X1126648Y1262649I0J-3203D01*
G01X1127462Y1261836D02*
G02X1128913Y1262437I1451J-1451D01*
G01X1132187Y1263587D02*
X1128913D01*
G01Y1262437D02*
X1131803D01*
G01X1134584Y1263588D02*
X1132188D01*
G01X1131804Y1262438D02*
X1134458D01*
G01X1144493Y1261393D02*
X1134584Y1263588D01*
G01X1134458Y1262438D02*
X1144046Y1260314D01*
G01X1134458Y1262438D02*
X1144046Y1260314D01*
G01X1144493Y1261393D02*
X1134584Y1263588D01*
G01X1131804Y1262438D02*
X1134458D01*
G01X1134584Y1263588D02*
X1132188D01*
G01X1128913Y1262437D02*
X1131803D01*
G01X1132187Y1263587D02*
X1128913D01*
G01X1127462Y1261836D02*
G02X1128913Y1262437I1451J-1451D01*
G01Y1263587D02*
G03X1126648Y1262649I0J-3203D01*
G01X1127097Y1260955D02*
G02X1127462Y1261836I1246J0D01*
G01X1126648Y1262649D02*
G03X1125947Y1260955I1695J-1693D01*
G01X1127097Y1259969D02*
Y1260955D01*
G01X1125947D02*
Y1259969D01*
G01X1132850Y1256500D02*
X1137256D01*
G01X1137129Y1255350D02*
X1132850D01*
G01X1130585Y1255562D02*
G02X1132850Y1256500I2265J-2265D01*
G01Y1255350D02*
G03X1131399Y1254749I0J-2052D01*
G01X1129884Y1253868D02*
G02X1130585Y1255562I2396J1D01*
G01X1131399Y1254749D02*
G03X1131034Y1253868I881J-881D01*
G01X1129884Y1252882D02*
Y1253868D01*
G01X1131034D02*
Y1252882D01*
G01Y1253868D02*
Y1252882D01*
G01X1129884D02*
Y1253868D01*
G01X1131399Y1254749D02*
G03X1131034Y1253868I881J-881D01*
G01X1129884D02*
G02X1130585Y1255562I2396J1D01*
G01X1132850Y1255350D02*
G03X1131399Y1254749I0J-2052D01*
G01X1130585Y1255562D02*
G02X1132850Y1256500I2265J-2265D01*
G01X1137129Y1255350D02*
X1132850D01*
G01Y1256500D02*
X1137256D01*
G01X1134282Y1249414D02*
X1139920Y1248163D01*
G01X1139473Y1247084D02*
X1134155Y1248264D01*
G01X1128913Y1249414D02*
X1134282D01*
G01X1134155Y1248264D02*
X1128913D01*
G01X1126648Y1248476D02*
G02X1128913Y1249414I2265J-2265D01*
G01Y1248264D02*
G03X1127462Y1247663I0J-2052D01*
G01X1125947Y1246782D02*
G02X1126648Y1248476I2396J1D01*
G01X1127462Y1247663D02*
G03X1127097Y1246782I881J-881D01*
G01X1125947Y1245796D02*
Y1246782D01*
G01X1127097D02*
Y1245796D01*
G01Y1246782D02*
Y1245796D01*
G01X1125947D02*
Y1246782D01*
G01X1127462Y1247663D02*
G03X1127097Y1246782I881J-881D01*
G01X1125947D02*
G02X1126648Y1248476I2396J1D01*
G01X1128913Y1248264D02*
G03X1127462Y1247663I0J-2052D01*
G01X1126648Y1248476D02*
G02X1128913Y1249414I2265J-2265D01*
G01X1134155Y1248264D02*
X1128913D01*
G01Y1249414D02*
X1134282D01*
G01X1139473Y1247084D02*
X1134155Y1248264D01*
G01X1134282Y1249414D02*
X1139920Y1248163D01*
G01X1098050Y1234303D02*
G03X1095784Y1235240I-2264J-2266D01*
G01X1095785Y1234090D02*
G02X1097236Y1233489I0J-2052D01*
G01X1098227Y1234105D02*
G03X1098050Y1234303I-1872J-1496D01*
G01X1097328Y1233386D02*
G02X1097601Y1232608I-972J-778D01*
G01X1097236Y1233489D02*
G02X1097328Y1233386I-882J-880D01*
G01X1098751Y1232610D02*
G03X1098227Y1234105I-2395J0D01*
G01X1097328Y1233386D02*
G02X1097601Y1232608I-972J-778D01*
G01X1097236Y1233489D02*
G02X1097328Y1233386I-882J-880D01*
G01X1098751Y1231622D02*
Y1232610D01*
G01X1097601Y1232608D02*
Y1231622D01*
G01Y1232608D02*
Y1231622D01*
G01X1098751D02*
Y1232610D01*
G01X1097328Y1233386D02*
G02X1097601Y1232608I-972J-778D01*
G01X1098227Y1234105D02*
G03X1098050Y1234303I-1872J-1496D01*
G01X1098751Y1232610D02*
G03X1098227Y1234105I-2395J0D01*
G01X1097236Y1233489D02*
G02X1097328Y1233386I-882J-880D01*
G01X1098227Y1234105D02*
G03X1098050Y1234303I-1872J-1496D01*
G01X1098751Y1232610D02*
G03X1098227Y1234105I-2395J0D01*
G01X1095785Y1234090D02*
G02X1097236Y1233489I0J-2052D01*
G01X1098050Y1234303D02*
G03X1095784Y1235240I-2264J-2266D01*
G01X1102688Y1239697D02*
Y1238709D01*
G01X1101538Y1239695D02*
Y1238709D01*
G01X1102164Y1241192D02*
G02X1102688Y1239697I-1871J-1495D01*
G01X1101265Y1240473D02*
G02X1101538Y1239695I-972J-778D01*
G01X1101173Y1240576D02*
G02X1101265Y1240473I-882J-880D01*
G01X1101987Y1241390D02*
G02X1102164Y1241192I-1695J-1694D01*
G01X1101265Y1240473D02*
G02X1101538Y1239695I-972J-778D01*
G01X1101173Y1240576D02*
G02X1101265Y1240473I-882J-880D01*
G01X1099721Y1242327D02*
G02X1101987Y1241390I2J-3203D01*
G01X1099722Y1241177D02*
G02X1101173Y1240576I0J-2052D01*
G01X1101538Y1239695D02*
Y1238709D01*
G01X1102688Y1239697D02*
Y1238709D01*
G01X1101265Y1240473D02*
G02X1101538Y1239695I-972J-778D01*
G01X1102164Y1241192D02*
G02X1102688Y1239697I-1871J-1495D01*
G01X1101987Y1241390D02*
G02X1102164Y1241192I-1695J-1694D01*
G01X1101173Y1240576D02*
G02X1101265Y1240473I-882J-880D01*
G01X1102164Y1241192D02*
G02X1102688Y1239697I-1871J-1495D01*
G01X1101987Y1241390D02*
G02X1102164Y1241192I-1695J-1694D01*
G01X1099722Y1241177D02*
G02X1101173Y1240576I0J-2052D01*
G01X1099721Y1242327D02*
G02X1101987Y1241390I2J-3203D01*
G01X1129884Y1282215D02*
Y1281229D01*
G01X1131034Y1282215D02*
Y1281229D01*
G01X1130585Y1283909D02*
G03X1129884Y1282215I1695J-1693D01*
G01X1131399Y1283096D02*
G03X1131034Y1282215I881J-881D01*
G01X1132850Y1284847D02*
G03X1130585Y1283909I0J-3203D01*
G01X1132850Y1283697D02*
G03X1131399Y1283096I0J-2052D01*
G01X1137930Y1284847D02*
X1132850D01*
G01X1137804Y1283697D02*
X1132850D01*
G01X1131034Y1282215D02*
Y1281229D01*
G01X1129884Y1282215D02*
Y1281229D01*
G01X1131399Y1283096D02*
G03X1131034Y1282215I881J-881D01*
G01X1130585Y1283909D02*
G03X1129884Y1282215I1695J-1693D01*
G01X1132850Y1283697D02*
G03X1131399Y1283096I0J-2052D01*
G01X1132850Y1284847D02*
G03X1130585Y1283909I0J-3203D01*
G01X1137804Y1283697D02*
X1132850D01*
G01X1137930Y1284847D02*
X1132850D01*
G01X1132396Y1277760D02*
X1146445Y1274652D01*
G01X1128913Y1277760D02*
X1132396D01*
G01X1128913Y1276610D02*
X1132270D01*
G01X1126648Y1276822D02*
G02X1128913Y1277760I2265J-2265D01*
G01X1132396D02*
X1146445Y1274652D01*
G01X1128913Y1276610D02*
X1132270D01*
G01X1128913Y1277760D02*
X1132396D01*
G01X1126648Y1276822D02*
G02X1128913Y1277760I2265J-2265D01*
G01X1102688Y1324737D02*
Y1323749D01*
G01X1101538Y1324735D02*
Y1323749D01*
G01Y1324735D02*
Y1323749D01*
G01X1102688Y1324737D02*
Y1323749D01*
G01X1098050Y1290997D02*
G03X1095784Y1291934I-2264J-2266D01*
G01X1095785Y1290784D02*
G02X1097236Y1290183I0J-2052D01*
G01X1098227Y1290799D02*
G03X1098050Y1290997I-1872J-1496D01*
G01X1097328Y1290080D02*
G02X1097601Y1289302I-972J-778D01*
G01X1097236Y1290183D02*
G02X1097328Y1290080I-882J-880D01*
G01X1098751Y1289304D02*
G03X1098227Y1290799I-2395J0D01*
G01X1097328Y1290080D02*
G02X1097601Y1289302I-972J-778D01*
G01X1097236Y1290183D02*
G02X1097328Y1290080I-882J-880D01*
G01X1098751Y1288316D02*
Y1289304D01*
G01X1097601Y1289302D02*
Y1288316D01*
G01Y1289302D02*
Y1288316D01*
G01X1098751D02*
Y1289304D01*
G01X1097328Y1290080D02*
G02X1097601Y1289302I-972J-778D01*
G01X1098227Y1290799D02*
G03X1098050Y1290997I-1872J-1496D01*
G01X1098751Y1289304D02*
G03X1098227Y1290799I-2395J0D01*
G01X1097236Y1290183D02*
G02X1097328Y1290080I-882J-880D01*
G01X1098227Y1290799D02*
G03X1098050Y1290997I-1872J-1496D01*
G01X1098751Y1289304D02*
G03X1098227Y1290799I-2395J0D01*
G01X1095785Y1290784D02*
G02X1097236Y1290183I0J-2052D01*
G01X1098050Y1290997D02*
G03X1095784Y1291934I-2264J-2266D01*
G01X1102688Y1296390D02*
Y1295402D01*
G01X1101538Y1296388D02*
Y1295402D01*
G01X1102164Y1297885D02*
G02X1102688Y1296390I-1871J-1495D01*
G01X1101265Y1297166D02*
G02X1101538Y1296388I-972J-778D01*
G01X1101173Y1297269D02*
G02X1101265Y1297166I-882J-880D01*
G01X1101987Y1298083D02*
G02X1102164Y1297885I-1695J-1694D01*
G01X1101265Y1297166D02*
G02X1101538Y1296388I-972J-778D01*
G01X1101173Y1297269D02*
G02X1101265Y1297166I-882J-880D01*
G01X1099721Y1299020D02*
G02X1101987Y1298083I2J-3203D01*
G01X1099722Y1297870D02*
G02X1101173Y1297269I0J-2052D01*
G01X1101538Y1296388D02*
Y1295402D01*
G01X1102688Y1296390D02*
Y1295402D01*
G01X1101265Y1297166D02*
G02X1101538Y1296388I-972J-778D01*
G01X1102164Y1297885D02*
G02X1102688Y1296390I-1871J-1495D01*
G01X1101987Y1298083D02*
G02X1102164Y1297885I-1695J-1694D01*
G01X1101173Y1297269D02*
G02X1101265Y1297166I-882J-880D01*
G01X1102164Y1297885D02*
G02X1102688Y1296390I-1871J-1495D01*
G01X1101987Y1298083D02*
G02X1102164Y1297885I-1695J-1694D01*
G01X1099722Y1297870D02*
G02X1101173Y1297269I0J-2052D01*
G01X1099721Y1299020D02*
G02X1101987Y1298083I2J-3203D01*
G01X1098050Y1305170D02*
G03X1095784Y1306107I-2264J-2266D01*
G01X1095785Y1304957D02*
G02X1097236Y1304356I0J-2052D01*
G01X1098227Y1304972D02*
G03X1098050Y1305170I-1872J-1496D01*
G01X1097328Y1304253D02*
G02X1097601Y1303475I-972J-778D01*
G01X1097236Y1304356D02*
G02X1097328Y1304253I-882J-880D01*
G01X1098751Y1303477D02*
G03X1098227Y1304972I-2395J0D01*
G01X1097328Y1304253D02*
G02X1097601Y1303475I-972J-778D01*
G01X1097236Y1304356D02*
G02X1097328Y1304253I-882J-880D01*
G01X1098751Y1302489D02*
Y1303477D01*
G01X1097601Y1303475D02*
Y1302489D01*
G01Y1303475D02*
Y1302489D01*
G01X1098751D02*
Y1303477D01*
G01X1097328Y1304253D02*
G02X1097601Y1303475I-972J-778D01*
G01X1098227Y1304972D02*
G03X1098050Y1305170I-1872J-1496D01*
G01X1098751Y1303477D02*
G03X1098227Y1304972I-2395J0D01*
G01X1097236Y1304356D02*
G02X1097328Y1304253I-882J-880D01*
G01X1098227Y1304972D02*
G03X1098050Y1305170I-1872J-1496D01*
G01X1098751Y1303477D02*
G03X1098227Y1304972I-2395J0D01*
G01X1095785Y1304957D02*
G02X1097236Y1304356I0J-2052D01*
G01X1098050Y1305170D02*
G03X1095784Y1306107I-2264J-2266D01*
G01X1102688Y1310563D02*
Y1309575D01*
G01X1101538Y1310561D02*
Y1309575D01*
G01X1102164Y1312058D02*
G02X1102688Y1310563I-1871J-1495D01*
G01X1101265Y1311339D02*
G02X1101538Y1310561I-972J-778D01*
G01X1101173Y1311442D02*
G02X1101265Y1311339I-882J-880D01*
G01X1101987Y1312256D02*
G02X1102164Y1312058I-1695J-1694D01*
G01X1101265Y1311339D02*
G02X1101538Y1310561I-972J-778D01*
G01X1101173Y1311442D02*
G02X1101265Y1311339I-882J-880D01*
G01X1099721Y1313193D02*
G02X1101987Y1312256I2J-3203D01*
G01X1099722Y1312043D02*
G02X1101173Y1311442I0J-2052D01*
G01X1101538Y1310561D02*
Y1309575D01*
G01X1102688Y1310563D02*
Y1309575D01*
G01X1101265Y1311339D02*
G02X1101538Y1310561I-972J-778D01*
G01X1102164Y1312058D02*
G02X1102688Y1310563I-1871J-1495D01*
G01X1101987Y1312256D02*
G02X1102164Y1312058I-1695J-1694D01*
G01X1101173Y1311442D02*
G02X1101265Y1311339I-882J-880D01*
G01X1102164Y1312058D02*
G02X1102688Y1310563I-1871J-1495D01*
G01X1101987Y1312256D02*
G02X1102164Y1312058I-1695J-1694D01*
G01X1099722Y1312043D02*
G02X1101173Y1311442I0J-2052D01*
G01X1099721Y1313193D02*
G02X1101987Y1312256I2J-3203D01*
G01X1098050Y1319343D02*
G03X1095784Y1320280I-2264J-2266D01*
G01X1095785Y1319130D02*
G02X1097236Y1318529I0J-2052D01*
G01X1098227Y1319145D02*
G03X1098050Y1319343I-1872J-1496D01*
G01X1097328Y1318426D02*
G02X1097601Y1317648I-972J-778D01*
G01X1097236Y1318529D02*
G02X1097328Y1318426I-882J-880D01*
G01X1098751Y1317650D02*
G03X1098227Y1319145I-2395J0D01*
G01X1097328Y1318426D02*
G02X1097601Y1317648I-972J-778D01*
G01X1097236Y1318529D02*
G02X1097328Y1318426I-882J-880D01*
G01X1098751Y1316662D02*
Y1317650D01*
G01X1097601Y1317648D02*
Y1316662D01*
G01Y1317648D02*
Y1316662D01*
G01X1098751D02*
Y1317650D01*
G01X1097328Y1318426D02*
G02X1097601Y1317648I-972J-778D01*
G01X1098227Y1319145D02*
G03X1098050Y1319343I-1872J-1496D01*
G01X1098751Y1317650D02*
G03X1098227Y1319145I-2395J0D01*
G01X1097236Y1318529D02*
G02X1097328Y1318426I-882J-880D01*
G01X1098227Y1319145D02*
G03X1098050Y1319343I-1872J-1496D01*
G01X1098751Y1317650D02*
G03X1098227Y1319145I-2395J0D01*
G01X1095785Y1319130D02*
G02X1097236Y1318529I0J-2052D01*
G01X1098050Y1319343D02*
G03X1095784Y1320280I-2264J-2266D01*
G01X1129884Y1353081D02*
Y1352095D01*
G01X1131034Y1353081D02*
Y1352095D01*
G01X1130585Y1354775D02*
G03X1129884Y1353081I1695J-1693D01*
G01X1131399Y1353962D02*
G03X1131034Y1353081I881J-881D01*
G01X1132850Y1355713D02*
G03X1130585Y1354775I0J-3203D01*
G01X1132850Y1354563D02*
G03X1131399Y1353962I0J-2052D01*
G01X1137211Y1355713D02*
X1132850D01*
G01X1137085Y1354563D02*
X1132850D01*
G01X1131034Y1353081D02*
Y1352095D01*
G01X1129884Y1353081D02*
Y1352095D01*
G01X1131399Y1353962D02*
G03X1131034Y1353081I881J-881D01*
G01X1130585Y1354775D02*
G03X1129884Y1353081I1695J-1693D01*
G01X1132850Y1354563D02*
G03X1131399Y1353962I0J-2052D01*
G01X1132850Y1355713D02*
G03X1130585Y1354775I0J-3203D01*
G01X1137085Y1354563D02*
X1132850D01*
G01X1137211Y1355713D02*
X1132850D01*
G01X1125947Y1345994D02*
Y1345008D01*
G01X1127097Y1345994D02*
Y1345008D01*
G01X1126648Y1347688D02*
G03X1125947Y1345994I1695J-1693D01*
G01X1127462Y1346875D02*
G03X1127097Y1345994I881J-881D01*
G01X1128913Y1348626D02*
G03X1126648Y1347688I0J-3203D01*
G01X1128913Y1347476D02*
G03X1127462Y1346875I0J-2052D01*
G01X1134808Y1348626D02*
X1128913D01*
G01X1134682Y1347476D02*
X1128913D01*
G01X1148706Y1345548D02*
X1134808Y1348626D01*
G01X1148259Y1344469D02*
X1134682Y1347476D01*
G01X1127097Y1345994D02*
Y1345008D01*
G01X1125947Y1345994D02*
Y1345008D01*
G01X1127462Y1346875D02*
G03X1127097Y1345994I881J-881D01*
G01X1126648Y1347688D02*
G03X1125947Y1345994I1695J-1693D01*
G01X1128913Y1347476D02*
G03X1127462Y1346875I0J-2052D01*
G01X1128913Y1348626D02*
G03X1126648Y1347688I0J-3203D01*
G01X1134682Y1347476D02*
X1128913D01*
G01X1134808Y1348626D02*
X1128913D01*
G01X1148259Y1344469D02*
X1134682Y1347476D01*
G01X1148706Y1345548D02*
X1134808Y1348626D01*
G01X1129884Y1338908D02*
Y1337922D01*
G01X1131034Y1338908D02*
Y1337922D01*
G01X1130585Y1340602D02*
G03X1129884Y1338908I1695J-1693D01*
G01X1131399Y1339789D02*
G03X1131034Y1338908I881J-881D01*
G01X1132850Y1341540D02*
G03X1130585Y1340602I0J-3203D01*
G01X1132850Y1340390D02*
G03X1131399Y1339789I0J-2052D01*
G01X1137547Y1341540D02*
X1132850D01*
G01X1137421Y1340390D02*
X1132850D01*
G01X1131034Y1338908D02*
Y1337922D01*
G01X1129884Y1338908D02*
Y1337922D01*
G01X1131399Y1339789D02*
G03X1131034Y1338908I881J-881D01*
G01X1130585Y1340602D02*
G03X1129884Y1338908I1695J-1693D01*
G01X1132850Y1340390D02*
G03X1131399Y1339789I0J-2052D01*
G01X1132850Y1341540D02*
G03X1130585Y1340602I0J-3203D01*
G01X1137421Y1340390D02*
X1132850D01*
G01X1137547Y1341540D02*
X1132850D01*
G01X1125947Y1331821D02*
Y1330835D01*
G01X1127097Y1331821D02*
Y1330835D01*
G01X1126648Y1333515D02*
G03X1125947Y1331821I1695J-1693D01*
G01X1127462Y1332702D02*
G03X1127097Y1331821I881J-881D01*
G01X1128913Y1334453D02*
G03X1126648Y1333515I0J-3203D01*
G01X1128913Y1333303D02*
G03X1127462Y1332702I0J-2052D01*
G01X1135155Y1334453D02*
X1128913D01*
G01X1135029Y1333303D02*
X1128913D01*
G01X1140081Y1333362D02*
X1135156Y1334454D01*
G01X1139634Y1332283D02*
X1135030Y1333304D01*
G01X1127097Y1331821D02*
Y1330835D01*
G01X1125947Y1331821D02*
Y1330835D01*
G01X1127462Y1332702D02*
G03X1127097Y1331821I881J-881D01*
G01X1126648Y1333515D02*
G03X1125947Y1331821I1695J-1693D01*
G01X1128913Y1333303D02*
G03X1127462Y1332702I0J-2052D01*
G01X1128913Y1334453D02*
G03X1126648Y1333515I0J-3203D01*
G01X1135029Y1333303D02*
X1128913D01*
G01X1135155Y1334453D02*
X1128913D01*
G01X1139634Y1332283D02*
X1135030Y1333304D01*
G01X1140081Y1333362D02*
X1135156Y1334454D01*
G01X1129884Y1367254D02*
Y1366268D01*
G01X1131034D02*
Y1367254D01*
G01X1130585Y1368948D02*
G03X1129884Y1367254I1695J-1693D01*
G01X1131034D02*
G02X1131399Y1368135I1246J0D01*
G01X1132850Y1369886D02*
G03X1130585Y1368948I0J-3203D01*
G01X1131399Y1368135D02*
G02X1132850Y1368736I1451J-1451D01*
G01X1145046Y1369886D02*
X1132850D01*
G01Y1368736D02*
X1144920D01*
G01X1132850D02*
X1144920D01*
G01X1145046Y1369886D02*
X1132850D01*
G01X1131399Y1368135D02*
G02X1132850Y1368736I1451J-1451D01*
G01Y1369886D02*
G03X1130585Y1368948I0J-3203D01*
G01X1131034Y1367254D02*
G02X1131399Y1368135I1246J0D01*
G01X1130585Y1368948D02*
G03X1129884Y1367254I1695J-1693D01*
G01X1131034Y1366268D02*
Y1367254D01*
G01X1129884D02*
Y1366268D01*
G01X1125947Y1360168D02*
Y1359182D01*
G01X1127097Y1360168D02*
Y1359182D01*
G01X1126648Y1361862D02*
G03X1125947Y1360168I1695J-1693D01*
G01X1127462Y1361049D02*
G03X1127097Y1360168I881J-881D01*
G01X1128913Y1362800D02*
G03X1126648Y1361862I0J-3203D01*
G01X1128913Y1361650D02*
G03X1127462Y1361049I0J-2052D01*
G01X1148580Y1362800D02*
X1128913D01*
G01X1148454Y1361650D02*
X1128913D01*
G01X1127097Y1360168D02*
Y1359182D01*
G01X1125947Y1360168D02*
Y1359182D01*
G01X1127462Y1361049D02*
G03X1127097Y1360168I881J-881D01*
G01X1126648Y1361862D02*
G03X1125947Y1360168I1695J-1693D01*
G01X1128913Y1361650D02*
G03X1127462Y1361049I0J-2052D01*
G01X1128913Y1362800D02*
G03X1126648Y1361862I0J-3203D01*
G01X1148454Y1361650D02*
X1128913D01*
G01X1148580Y1362800D02*
X1128913D01*
G01X1102164Y1326232D02*
G02X1102688Y1324737I-1871J-1495D01*
G01X1101265Y1325513D02*
G02X1101538Y1324735I-972J-778D01*
G01X1101173Y1325616D02*
G02X1101265Y1325513I-882J-880D01*
G01X1101987Y1326430D02*
G02X1102164Y1326232I-1695J-1694D01*
G01X1101265Y1325513D02*
G02X1101538Y1324735I-972J-778D01*
G01X1101173Y1325616D02*
G02X1101265Y1325513I-882J-880D01*
G01X1099721Y1327367D02*
G02X1101987Y1326430I2J-3203D01*
G01X1099722Y1326217D02*
G02X1101173Y1325616I0J-2052D01*
G01X1101265Y1325513D02*
G02X1101538Y1324735I-972J-778D01*
G01X1102164Y1326232D02*
G02X1102688Y1324737I-1871J-1495D01*
G01X1101987Y1326430D02*
G02X1102164Y1326232I-1695J-1694D01*
G01X1101173Y1325616D02*
G02X1101265Y1325513I-882J-880D01*
G01X1102164Y1326232D02*
G02X1102688Y1324737I-1871J-1495D01*
G01X1101987Y1326430D02*
G02X1102164Y1326232I-1695J-1694D01*
G01X1099722Y1326217D02*
G02X1101173Y1325616I0J-2052D01*
G01X1099721Y1327367D02*
G02X1101987Y1326430I2J-3203D01*
G01X1098050Y1376036D02*
G03X1095784Y1376973I-2264J-2266D01*
G01X1095785Y1375823D02*
G02X1097236Y1375222I0J-2052D01*
G01X1098227Y1375838D02*
G03X1098050Y1376036I-1872J-1496D01*
G01X1097328Y1375119D02*
G02X1097601Y1374341I-972J-778D01*
G01X1097236Y1375222D02*
G02X1097328Y1375119I-882J-880D01*
G01X1098751Y1374343D02*
G03X1098227Y1375838I-2395J0D01*
G01X1097328Y1375119D02*
G02X1097601Y1374341I-972J-778D01*
G01X1097236Y1375222D02*
G02X1097328Y1375119I-882J-880D01*
G01X1098751Y1373355D02*
Y1374343D01*
G01X1097601Y1374341D02*
Y1373355D01*
G01Y1374341D02*
Y1373355D01*
G01X1098751D02*
Y1374343D01*
G01X1097328Y1375119D02*
G02X1097601Y1374341I-972J-778D01*
G01X1098227Y1375838D02*
G03X1098050Y1376036I-1872J-1496D01*
G01X1098751Y1374343D02*
G03X1098227Y1375838I-2395J0D01*
G01X1097236Y1375222D02*
G02X1097328Y1375119I-882J-880D01*
G01X1098227Y1375838D02*
G03X1098050Y1376036I-1872J-1496D01*
G01X1098751Y1374343D02*
G03X1098227Y1375838I-2395J0D01*
G01X1095785Y1375823D02*
G02X1097236Y1375222I0J-2052D01*
G01X1098050Y1376036D02*
G03X1095784Y1376973I-2264J-2266D01*
G01X1102688Y1381430D02*
Y1380442D01*
G01X1101538Y1381428D02*
Y1380442D01*
G01X1102164Y1382925D02*
G02X1102688Y1381430I-1871J-1495D01*
G01X1101265Y1382206D02*
G02X1101538Y1381428I-972J-778D01*
G01X1101173Y1382309D02*
G02X1101265Y1382206I-882J-880D01*
G01X1101987Y1383123D02*
G02X1102164Y1382925I-1695J-1694D01*
G01X1101265Y1382206D02*
G02X1101538Y1381428I-972J-778D01*
G01X1101173Y1382309D02*
G02X1101265Y1382206I-882J-880D01*
G01X1099721Y1384060D02*
G02X1101987Y1383123I2J-3203D01*
G01X1099722Y1382910D02*
G02X1101173Y1382309I0J-2052D01*
G01X1101538Y1381428D02*
Y1380442D01*
G01X1102688Y1381430D02*
Y1380442D01*
G01X1101265Y1382206D02*
G02X1101538Y1381428I-972J-778D01*
G01X1102164Y1382925D02*
G02X1102688Y1381430I-1871J-1495D01*
G01X1101987Y1383123D02*
G02X1102164Y1382925I-1695J-1694D01*
G01X1101173Y1382309D02*
G02X1101265Y1382206I-882J-880D01*
G01X1102164Y1382925D02*
G02X1102688Y1381430I-1871J-1495D01*
G01X1101987Y1383123D02*
G02X1102164Y1382925I-1695J-1694D01*
G01X1099722Y1382910D02*
G02X1101173Y1382309I0J-2052D01*
G01X1099721Y1384060D02*
G02X1101987Y1383123I2J-3203D01*
G01X1098050Y1390209D02*
G03X1095784Y1391146I-2264J-2266D01*
G01X1095785Y1389996D02*
G02X1097236Y1389395I0J-2052D01*
G01X1098227Y1390011D02*
G03X1098050Y1390209I-1872J-1496D01*
G01X1097328Y1389292D02*
G02X1097601Y1388514I-972J-778D01*
G01X1097236Y1389395D02*
G02X1097328Y1389292I-882J-880D01*
G01X1098751Y1388516D02*
G03X1098227Y1390011I-2395J0D01*
G01X1097328Y1389292D02*
G02X1097601Y1388514I-972J-778D01*
G01X1097236Y1389395D02*
G02X1097328Y1389292I-882J-880D01*
G01X1098751Y1387528D02*
Y1388516D01*
G01X1097601Y1388514D02*
Y1387528D01*
G01Y1388514D02*
Y1387528D01*
G01X1098751D02*
Y1388516D01*
G01X1097328Y1389292D02*
G02X1097601Y1388514I-972J-778D01*
G01X1098227Y1390011D02*
G03X1098050Y1390209I-1872J-1496D01*
G01X1098751Y1388516D02*
G03X1098227Y1390011I-2395J0D01*
G01X1097236Y1389395D02*
G02X1097328Y1389292I-882J-880D01*
G01X1098227Y1390011D02*
G03X1098050Y1390209I-1872J-1496D01*
G01X1098751Y1388516D02*
G03X1098227Y1390011I-2395J0D01*
G01X1095785Y1389996D02*
G02X1097236Y1389395I0J-2052D01*
G01X1098050Y1390209D02*
G03X1095784Y1391146I-2264J-2266D01*
G01X1102688Y1395603D02*
Y1394615D01*
G01X1101538Y1395601D02*
Y1394615D01*
G01X1102164Y1397098D02*
G02X1102688Y1395603I-1871J-1495D01*
G01X1101265Y1396379D02*
G02X1101538Y1395601I-972J-778D01*
G01X1101173Y1396482D02*
G02X1101265Y1396379I-882J-880D01*
G01X1101987Y1397296D02*
G02X1102164Y1397098I-1695J-1694D01*
G01X1101265Y1396379D02*
G02X1101538Y1395601I-972J-778D01*
G01X1101173Y1396482D02*
G02X1101265Y1396379I-882J-880D01*
G01X1099721Y1398233D02*
G02X1101987Y1397296I2J-3203D01*
G01X1099722Y1397083D02*
G02X1101173Y1396482I0J-2052D01*
G01X1101538Y1395601D02*
Y1394615D01*
G01X1102688Y1395603D02*
Y1394615D01*
G01X1101265Y1396379D02*
G02X1101538Y1395601I-972J-778D01*
G01X1102164Y1397098D02*
G02X1102688Y1395603I-1871J-1495D01*
G01X1101987Y1397296D02*
G02X1102164Y1397098I-1695J-1694D01*
G01X1101173Y1396482D02*
G02X1101265Y1396379I-882J-880D01*
G01X1102164Y1397098D02*
G02X1102688Y1395603I-1871J-1495D01*
G01X1101987Y1397296D02*
G02X1102164Y1397098I-1695J-1694D01*
G01X1099722Y1397083D02*
G02X1101173Y1396482I0J-2052D01*
G01X1099721Y1398233D02*
G02X1101987Y1397296I2J-3203D01*
G01X1098050Y1404382D02*
G03X1095784Y1405319I-2264J-2266D01*
G01X1095785Y1404169D02*
G02X1097236Y1403568I0J-2052D01*
G01X1098227Y1404184D02*
G03X1098050Y1404382I-1872J-1496D01*
G01X1097328Y1403465D02*
G02X1097601Y1402687I-972J-778D01*
G01X1097236Y1403568D02*
G02X1097328Y1403465I-882J-880D01*
G01X1098751Y1402689D02*
G03X1098227Y1404184I-2395J0D01*
G01X1097328Y1403465D02*
G02X1097601Y1402687I-972J-778D01*
G01X1097236Y1403568D02*
G02X1097328Y1403465I-882J-880D01*
G01X1098751Y1401701D02*
Y1402689D01*
G01X1097601Y1402687D02*
Y1401701D01*
G01Y1402687D02*
Y1401701D01*
G01X1098751D02*
Y1402689D01*
G01X1097328Y1403465D02*
G02X1097601Y1402687I-972J-778D01*
G01X1098227Y1404184D02*
G03X1098050Y1404382I-1872J-1496D01*
G01X1098751Y1402689D02*
G03X1098227Y1404184I-2395J0D01*
G01X1097236Y1403568D02*
G02X1097328Y1403465I-882J-880D01*
G01X1098227Y1404184D02*
G03X1098050Y1404382I-1872J-1496D01*
G01X1098751Y1402689D02*
G03X1098227Y1404184I-2395J0D01*
G01X1095785Y1404169D02*
G02X1097236Y1403568I0J-2052D01*
G01X1098050Y1404382D02*
G03X1095784Y1405319I-2264J-2266D01*
G01X1102688Y1409776D02*
Y1408788D01*
G01X1101538Y1409774D02*
Y1408788D01*
G01X1102164Y1411271D02*
G02X1102688Y1409776I-1871J-1495D01*
G01X1101265Y1410552D02*
G02X1101538Y1409774I-972J-778D01*
G01X1101173Y1410655D02*
G02X1101265Y1410552I-882J-880D01*
G01X1101987Y1411469D02*
G02X1102164Y1411271I-1695J-1694D01*
G01X1101265Y1410552D02*
G02X1101538Y1409774I-972J-778D01*
G01X1101173Y1410655D02*
G02X1101265Y1410552I-882J-880D01*
G01X1099721Y1412406D02*
G02X1101987Y1411469I2J-3203D01*
G01X1099722Y1411256D02*
G02X1101173Y1410655I0J-2052D01*
G01X1101538Y1409774D02*
Y1408788D01*
G01X1102688Y1409776D02*
Y1408788D01*
G01X1101265Y1410552D02*
G02X1101538Y1409774I-972J-778D01*
G01X1102164Y1411271D02*
G02X1102688Y1409776I-1871J-1495D01*
G01X1101987Y1411469D02*
G02X1102164Y1411271I-1695J-1694D01*
G01X1101173Y1410655D02*
G02X1101265Y1410552I-882J-880D01*
G01X1102164Y1411271D02*
G02X1102688Y1409776I-1871J-1495D01*
G01X1101987Y1411469D02*
G02X1102164Y1411271I-1695J-1694D01*
G01X1099722Y1411256D02*
G02X1101173Y1410655I0J-2052D01*
G01X1099721Y1412406D02*
G02X1101987Y1411469I2J-3203D01*
G01X1154607Y1175326D02*
X1198005Y1107211D01*
G01X1196926Y1106764D02*
X1162346Y1161039D01*
G01X1154607Y1175326D02*
X1198005Y1107211D01*
G01X1154607Y1175326D02*
X1198005Y1107211D01*
G01X1154607Y1175326D02*
X1198005Y1107211D01*
G01X1196926Y1106764D02*
X1162346Y1161039D01*
G01X1154607Y1175326D02*
X1198005Y1107211D01*
G01X1193462Y1099607D02*
X1148537Y1170125D01*
G01X1192383Y1099160D02*
X1155622Y1156863D01*
G01X1193462Y1099607D02*
X1148537Y1170125D01*
G01X1193462Y1099607D02*
X1148537Y1170125D01*
G01X1193462Y1099607D02*
X1148537Y1170125D01*
G01X1192383Y1099160D02*
X1155622Y1156863D01*
G01X1193462Y1099607D02*
X1148537Y1170125D01*
G01X1165974Y1183028D02*
X1208664Y1116012D01*
G01X1168247Y1177317D02*
X1167442Y1178582D01*
G01X1170547Y1173707D02*
X1169741Y1174972D01*
G01X1207584Y1115565D02*
X1172041Y1171363D01*
G01X1165974Y1183028D02*
X1208664Y1116012D01*
G01X1168247Y1177317D02*
X1167442Y1178582D01*
G01X1165974Y1183028D02*
X1208664Y1116012D01*
G01X1170547Y1173707D02*
X1169741Y1174972D01*
G01X1165974Y1183028D02*
X1208664Y1116012D01*
G01X1207584Y1115565D02*
X1172041Y1171363D01*
G01X1165974Y1183028D02*
X1208664Y1116012D01*
G01X1160615Y1178914D02*
X1203124Y1112163D01*
G01X1168429Y1164502D02*
X1202045Y1111716D01*
G01X1166130Y1168112D02*
X1166936Y1166847D01*
G01X1163831Y1171722D02*
X1164637Y1170457D01*
G01X1159782Y1178081D02*
X1162338Y1174067D01*
G01X1141460Y1191115D02*
X1160615Y1178914D01*
G01X1141013Y1190036D02*
X1159782Y1178081D01*
G01X1168429Y1164502D02*
X1202045Y1111716D01*
G01X1160615Y1178914D02*
X1203124Y1112163D01*
G01X1166130Y1168112D02*
X1166936Y1166847D01*
G01X1160615Y1178914D02*
X1203124Y1112163D01*
G01X1163831Y1171722D02*
X1164637Y1170457D01*
G01X1160615Y1178914D02*
X1203124Y1112163D01*
G01X1159782Y1178081D02*
X1162338Y1174067D01*
G01X1160615Y1178914D02*
X1203124Y1112163D01*
G01X1141013Y1190036D02*
X1159782Y1178081D01*
G01X1141460Y1191115D02*
X1160615Y1178914D01*
G01X1156252Y1170603D02*
X1153774Y1174493D01*
G01X1158552Y1166993D02*
X1157746Y1168258D01*
G01X1160852Y1163384D02*
X1160046Y1164649D01*
G01X1139518Y1184942D02*
X1154607Y1175326D01*
G01X1153774Y1174493D02*
X1139070Y1183863D01*
G01X1153774Y1174493D02*
X1139070Y1183863D01*
G01X1139518Y1184942D02*
X1154607Y1175326D01*
G01X1156252Y1170603D02*
X1153774Y1174493D01*
G01X1158552Y1166993D02*
X1157746Y1168258D01*
G01X1160852Y1163384D02*
X1160046Y1164649D01*
G01X1147703Y1169292D02*
X1147704D01*
G01X1149528Y1166427D02*
X1147703Y1169292D01*
G01X1151828Y1162817D02*
X1151022Y1164082D01*
G01X1154128Y1159208D02*
X1153322Y1160473D01*
G01X1147703Y1169292D02*
X1147704D01*
G01X1149528Y1166427D02*
X1147703Y1169292D01*
G01X1151828Y1162817D02*
X1151022Y1164082D01*
G01X1154128Y1159208D02*
X1153322Y1160473D01*
G01X1185397Y1224560D02*
X1184591Y1225825D01*
G01X1185397Y1224560D02*
X1184591Y1225825D01*
G01X1224355Y1153257D02*
X1162559Y1249878D01*
G01X1181145Y1218682D02*
X1223276Y1152809D01*
G01X1178839Y1222288D02*
X1179647Y1221024D01*
G01X1176533Y1225893D02*
X1177341Y1224630D01*
G01X1181145Y1218682D02*
X1223276Y1152809D01*
G01X1224355Y1153257D02*
X1162559Y1249878D01*
G01X1178839Y1222288D02*
X1179647Y1221024D01*
G01X1224355Y1153257D02*
X1162559Y1249878D01*
G01X1176533Y1225893D02*
X1177341Y1224630D01*
G01X1224355Y1153257D02*
X1162559Y1249878D01*
G01X1224355Y1153257D02*
X1162559Y1249878D01*
G01X1156505Y1246467D02*
X1214032Y1156110D01*
G01X1169421Y1224038D02*
X1155672Y1245634D01*
G01X1171720Y1220427D02*
X1170914Y1221693D01*
G01X1174018Y1216817D02*
X1173213Y1218082D01*
G01X1212953Y1155663D02*
X1175511Y1214472D01*
G01X1169421Y1224038D02*
X1155672Y1245634D01*
G01X1156505Y1246467D02*
X1214032Y1156110D01*
G01X1171720Y1220427D02*
X1170914Y1221693D01*
G01X1156505Y1246467D02*
X1214032Y1156110D01*
G01X1174018Y1216817D02*
X1173213Y1218082D01*
G01X1156505Y1246467D02*
X1214032Y1156110D01*
G01X1212953Y1155663D02*
X1175511Y1214472D01*
G01X1156505Y1246467D02*
X1214032Y1156110D01*
G01X1152440Y1240188D02*
X1206265Y1155636D01*
G01X1162123Y1222835D02*
X1151607Y1239355D01*
G01X1164422Y1219224D02*
X1163616Y1220490D01*
G01X1166720Y1215614D02*
X1165915Y1216879D01*
G01X1205185Y1155189D02*
X1168213Y1213269D01*
G01X1162123Y1222835D02*
X1151607Y1239355D01*
G01X1152440Y1240188D02*
X1206265Y1155636D01*
G01X1164422Y1219224D02*
X1163616Y1220490D01*
G01X1152440Y1240188D02*
X1206265Y1155636D01*
G01X1166720Y1215614D02*
X1165915Y1216879D01*
G01X1152440Y1240188D02*
X1206265Y1155636D01*
G01X1205185Y1155189D02*
X1168213Y1213269D01*
G01X1152440Y1240188D02*
X1206265Y1155636D01*
G01X1165948Y1180927D02*
X1165142Y1182192D01*
G01X1141715Y1198331D02*
X1165974Y1183028D01*
G01X1165142Y1182192D02*
X1141270Y1197251D01*
G01X1165142Y1182192D02*
X1141270Y1197251D01*
G01X1141715Y1198331D02*
X1165974Y1183028D01*
G01X1165948Y1180927D02*
X1165142Y1182192D01*
G01X1138497Y1185169D02*
X1139518Y1184942D01*
G01X1138658Y1183955D02*
X1136268Y1184484D01*
G01X1139070Y1183863D02*
X1138658Y1183955D01*
G01X1136394Y1185634D02*
X1138497Y1185169D01*
G01X1138658Y1183955D02*
X1136268Y1184484D01*
G01X1138658Y1183955D02*
X1136268Y1184484D01*
G01X1138497Y1185169D02*
X1139518Y1184942D01*
G01X1136394Y1185634D02*
X1138497Y1185169D01*
G01X1139070Y1183863D02*
X1138658Y1183955D01*
G01X1138497Y1185169D02*
X1139518Y1184942D01*
G01X1180792Y1260135D02*
X1144175Y1283462D01*
G01X1179959Y1259302D02*
X1143728Y1282383D01*
G01X1258901Y1137512D02*
X1180792Y1260135D01*
G01X1188504Y1245887D02*
X1179959Y1259302D01*
G01D02*
X1143728Y1282383D01*
G01X1180792Y1260135D02*
X1144175Y1283462D01*
G01X1188504Y1245887D02*
X1179959Y1259302D01*
G01X1258901Y1137512D02*
X1180792Y1260135D01*
G01X1258901Y1137512D02*
X1180792Y1260135D01*
G01X1258901Y1137512D02*
X1180792Y1260135D01*
G01X1258901Y1137512D02*
X1180792Y1260135D01*
G01X1174083Y1257043D02*
X1253847Y1131817D01*
G01X1173250Y1256210D02*
X1186895Y1234788D01*
G01X1146445Y1274652D02*
X1174083Y1257043D01*
G01X1145998Y1273573D02*
X1173250Y1256210D01*
G01X1174083Y1257043D02*
X1253847Y1131817D01*
G01X1174083Y1257043D02*
X1253847Y1131817D01*
G01X1174083Y1257043D02*
X1253847Y1131817D01*
G01X1174083Y1257043D02*
X1253847Y1131817D01*
G01X1173250Y1256210D02*
X1186895Y1234788D01*
G01X1174083Y1257043D02*
X1253847Y1131817D01*
G01X1145998Y1273573D02*
X1173250Y1256210D01*
G01X1146445Y1274652D02*
X1174083Y1257043D01*
G01X1168331Y1253478D02*
X1144468Y1268681D01*
G01X1167498Y1252645D02*
X1144021Y1267602D01*
G01X1233921Y1150563D02*
X1168331Y1253478D01*
G01X1180797Y1231778D02*
X1167498Y1252645D01*
G01X1183097Y1228169D02*
X1182291Y1229434D01*
G01X1167498Y1252645D02*
X1144021Y1267602D01*
G01X1168331Y1253478D02*
X1144468Y1268681D01*
G01X1180797Y1231778D02*
X1167498Y1252645D01*
G01X1233921Y1150563D02*
X1168331Y1253478D01*
G01X1183097Y1228169D02*
X1182291Y1229434D01*
G01X1233921Y1150563D02*
X1168331Y1253478D01*
G01X1233921Y1150563D02*
X1168331Y1253478D01*
G01X1233921Y1150563D02*
X1168331Y1253478D01*
G01X1162559Y1249878D02*
X1144493Y1261393D01*
G01X1144046Y1260314D02*
X1161726Y1249044D01*
G01D02*
X1175035Y1228235D01*
G01X1161726Y1249044D02*
X1175035Y1228235D01*
G01X1144046Y1260314D02*
X1161726Y1249044D01*
G01X1162559Y1249878D02*
X1144493Y1261393D01*
G01X1142624Y1255305D02*
X1156505Y1246467D01*
G01X1155672Y1245634D02*
X1142177Y1254226D01*
G01X1137256Y1256500D02*
X1142624Y1255305D01*
G01X1142177Y1254226D02*
X1137129Y1255350D01*
G01X1142177Y1254226D02*
X1137129Y1255350D01*
G01X1137256Y1256500D02*
X1142624Y1255305D01*
G01X1155672Y1245634D02*
X1142177Y1254226D01*
G01X1142624Y1255305D02*
X1156505Y1246467D01*
G01X1139920Y1248163D02*
X1152440Y1240188D01*
G01X1151607Y1239355D02*
X1139473Y1247084D01*
G01X1151607Y1239355D02*
X1139473Y1247084D01*
G01X1139920Y1248163D02*
X1152440Y1240188D01*
G01X1182647Y1323926D02*
X1148706Y1345548D01*
G01X1181813Y1323093D02*
X1148259Y1344469D01*
G01X1203771Y1290732D02*
X1182647Y1323926D01*
G01X1195819Y1301084D02*
X1181813Y1323093D01*
G01D02*
X1148259Y1344469D01*
G01X1182647Y1323926D02*
X1148706Y1345548D01*
G01X1195819Y1301084D02*
X1181813Y1323093D01*
G01X1203771Y1290732D02*
X1182647Y1323926D01*
G01X1203771Y1290732D02*
X1182647Y1323926D01*
G01X1203771Y1290732D02*
X1182647Y1323926D01*
G01X1203771Y1290732D02*
X1182647Y1323926D01*
G01X1215681Y1243612D02*
X1160245Y1330626D01*
G01X1207587Y1254175D02*
X1159412Y1329793D01*
G01X1207587Y1254175D02*
X1159412Y1329793D01*
G01X1215681Y1243612D02*
X1160245Y1330626D01*
G01X1215681Y1243612D02*
X1160245Y1330626D01*
G01X1215681Y1243612D02*
X1160245Y1330626D01*
G01X1215681Y1243612D02*
X1160245Y1330626D01*
G01X1157617Y1322191D02*
X1140081Y1333362D01*
G01X1156784Y1321358D02*
X1139634Y1332283D01*
G01X1259886Y1161666D02*
X1157617Y1322191D01*
G01X1241760Y1187976D02*
X1156784Y1321358D01*
G01D02*
X1139634Y1332283D01*
G01X1157617Y1322191D02*
X1140081Y1333362D01*
G01X1241760Y1187976D02*
X1156784Y1321358D01*
G01X1259886Y1161666D02*
X1157617Y1322191D01*
G01X1259886Y1161666D02*
X1157617Y1322191D01*
G01X1259886Y1161666D02*
X1157617Y1322191D01*
G01X1259886Y1161666D02*
X1157617Y1322191D01*
G01X1144175Y1283462D02*
X1137930Y1284847D01*
G01X1143728Y1282383D02*
X1137804Y1283697D01*
G01X1143728Y1282383D02*
X1137804Y1283697D01*
G01X1144175Y1283462D02*
X1137930Y1284847D01*
G01X1148072Y1353306D02*
X1137211Y1355713D01*
G01X1147625Y1352227D02*
X1137085Y1354563D01*
G01X1189838Y1326698D02*
X1148072Y1353306D01*
G01X1189005Y1325865D02*
X1147625Y1352227D01*
G01D02*
X1137085Y1354563D01*
G01X1148072Y1353306D02*
X1137211Y1355713D01*
G01X1189005Y1325865D02*
X1147625Y1352227D01*
G01X1189838Y1326698D02*
X1148072Y1353306D01*
G01X1146057Y1339657D02*
X1137547Y1341540D01*
G01X1145610Y1338577D02*
X1137421Y1340390D01*
G01X1160245Y1330626D02*
X1146057Y1339657D01*
G01X1159412Y1329793D02*
X1145610Y1338577D01*
G01D02*
X1137421Y1340390D01*
G01X1146057Y1339657D02*
X1137547Y1341540D01*
G01X1159412Y1329793D02*
X1145610Y1338577D01*
G01X1160245Y1330626D02*
X1146057Y1339657D01*
G01X1325983Y1329774D02*
X1145046Y1369886D01*
G01X1144920Y1368736D02*
X1325536Y1328695D01*
G01X1144920Y1368736D02*
X1325536Y1328695D01*
G01X1325983Y1329774D02*
X1145046Y1369886D01*
G01X1316877Y1325493D02*
X1148580Y1362800D01*
G01X1316427Y1324414D02*
X1148454Y1361650D01*
G01X1316427Y1324414D02*
X1148454Y1361650D01*
G01X1316877Y1325493D02*
X1148580Y1362800D01*
G01X1245389Y612882D02*
X1193181Y848427D01*
G01X1244314Y612416D02*
X1192003Y848427D01*
G01X1244314Y612416D02*
X1192003Y848427D01*
G01X1245389Y612882D02*
X1193181Y848427D01*
G01X1207096Y847805D02*
X1258150Y617810D01*
G01X1205918Y847805D02*
X1257075Y617342D01*
G01X1205918Y847805D02*
X1257075Y617342D01*
G01X1207096Y847805D02*
X1258150Y617810D01*
G01X1200209Y849355D02*
X1252441Y613774D01*
G01X1251366Y613306D02*
X1199086Y849107D01*
G01X1251366Y613306D02*
X1199086Y849107D01*
G01X1251366Y613306D02*
X1199086Y849107D01*
G01X1200209Y849355D02*
X1252441Y613774D01*
G01X1215097Y854409D02*
X1267700Y617171D01*
G01X1266625Y616702D02*
X1213977Y854145D01*
G01X1266625Y616702D02*
X1213977Y854145D01*
G01X1215097Y854409D02*
X1267700Y617171D01*
G01X1222810Y860882D02*
X1270354Y646680D01*
G01X1269277Y646223D02*
X1221632Y860882D01*
G01X1269277Y646223D02*
X1221632Y860882D01*
G01X1222810D02*
X1270354Y646680D01*
G01X1247121Y970551D02*
X1222810Y860882D01*
G01X1221632D02*
X1245943Y970552D01*
G01X1221632Y860882D02*
X1245943Y970552D01*
G01X1247121Y970551D02*
X1222810Y860882D01*
G01X1240802Y970379D02*
X1215096Y854413D01*
G01X1213973Y854663D02*
X1239624Y970380D01*
G01X1213914Y854397D02*
X1213973Y854663D01*
G01D02*
X1239624Y970380D01*
G01X1240802Y970379D02*
X1215096Y854413D01*
G01X1213914Y854397D02*
X1213973Y854663D01*
G01X1240802Y970379D02*
X1215096Y854413D01*
G01X1234428Y971017D02*
X1207096Y847805D01*
G01X1233250Y971017D02*
X1205918Y847805D01*
G01X1233250Y971017D02*
X1205918Y847805D01*
G01X1234428Y971017D02*
X1207096Y847805D01*
G01X1200165Y849554D02*
X1200209Y849356D01*
G01X1227645Y973479D02*
X1200163Y849557D01*
G01X1198937Y849341D02*
X1226467Y973479D01*
G01X1198937Y849341D02*
X1226467Y973479D01*
G01X1227645D02*
X1200163Y849557D01*
G01X1200165Y849554D02*
X1200209Y849356D01*
G01X1193181Y848427D02*
X1221164Y974681D01*
G01X1192003Y848427D02*
X1219986Y974681D01*
G01X1192003Y848427D02*
X1219986Y974681D01*
G01X1193181Y848427D02*
X1221164Y974681D01*
G01X1203124Y1112163D02*
X1234428Y971017D01*
G01X1202045Y1111716D02*
X1233250Y971017D01*
G01X1202045Y1111716D02*
X1233250Y971017D01*
G01X1203124Y1112163D02*
X1234428Y971017D01*
G01X1198005Y1107211D02*
X1227645Y973479D01*
G01X1226467D02*
X1196926Y1106764D01*
G01X1226467Y973479D02*
X1196926Y1106764D01*
G01X1198005Y1107211D02*
X1227645Y973479D01*
G01X1221164Y974681D02*
X1193462Y1099607D01*
G01X1219986Y974681D02*
X1192383Y1099160D01*
G01X1219986Y974681D02*
X1192383Y1099160D01*
G01X1221164Y974681D02*
X1193462Y1099607D01*
G01X1233207Y1028249D02*
X1205185Y1155189D01*
G01X1233207Y1028249D02*
X1205185Y1155189D01*
G01X1208664Y1116012D02*
X1240802Y970379D01*
G01X1239624Y970380D02*
X1207584Y1115565D01*
G01X1239624Y970380D02*
X1207584Y1115565D01*
G01X1208664Y1116012D02*
X1240802Y970379D01*
G01X1230933Y1079875D02*
X1334527Y917269D01*
G01X1333448Y916822D02*
X1229854Y1079428D01*
G01X1214032Y1156110D02*
X1230933Y1079875D01*
G01X1229854Y1079428D02*
X1212953Y1155663D01*
G01X1229854Y1079428D02*
X1212953Y1155663D01*
G01X1214032Y1156110D02*
X1230933Y1079875D01*
G01X1333448Y916822D02*
X1229854Y1079428D01*
G01X1230933Y1079875D02*
X1334527Y917269D01*
G01X1206265Y1155636D02*
X1234330Y1028497D01*
G01X1206265Y1155636D02*
X1234330Y1028497D01*
G01X1239438Y1085227D02*
X1224355Y1153257D01*
G01X1223276Y1152809D02*
X1238359Y1084780D01*
G01X1223276Y1152809D02*
X1238359Y1084780D01*
G01X1239438Y1085227D02*
X1224355Y1153257D01*
G01X1257822Y1137065D02*
X1194596Y1236323D01*
G01X1257822Y1137065D02*
X1194596Y1236323D01*
G01X1222877Y1178297D02*
X1252768Y1131370D01*
G01X1192987Y1225223D02*
X1222877Y1178297D01*
G01D02*
X1252768Y1131370D01*
G01X1192987Y1225223D02*
X1222877Y1178297D01*
G01X1232842Y1150116D02*
X1186891Y1222215D01*
G01X1246784Y1087240D02*
X1232842Y1150116D01*
G01D02*
X1186891Y1222215D01*
G01X1246784Y1087240D02*
X1232842Y1150116D01*
G01X1190688Y1228833D02*
X1191493Y1227568D01*
G01X1190688Y1228833D02*
X1191493Y1227568D01*
G01X1380952Y1173457D02*
X1203771Y1290732D01*
G01X1380503Y1172374D02*
X1202932Y1289908D01*
G01X1380503Y1172374D02*
X1202932Y1289908D01*
G01X1380952Y1173457D02*
X1203771Y1290732D01*
G01X1209887Y1250566D02*
X1209081Y1251831D01*
G01X1212187Y1246956D02*
X1211381Y1248221D01*
G01X1214842Y1242788D02*
X1213680Y1244611D01*
G01X1335338Y1164408D02*
X1215681Y1243613D01*
G01X1334705Y1163447D02*
X1214842Y1242788D01*
G01X1334705Y1163447D02*
X1214842Y1242788D01*
G01X1334705Y1163447D02*
X1214842Y1242788D01*
G01X1209887Y1250566D02*
X1209081Y1251831D01*
G01X1212187Y1246956D02*
X1211381Y1248221D01*
G01X1214842Y1242788D02*
X1213680Y1244611D01*
G01X1334705Y1163447D02*
X1214842Y1242788D01*
G01X1335338Y1164408D02*
X1215681Y1243613D01*
G01X1190803Y1242277D02*
X1189997Y1243542D01*
G01X1193103Y1238667D02*
X1192297Y1239932D01*
G01X1190803Y1242277D02*
X1189997Y1243542D01*
G01X1193103Y1238667D02*
X1192297Y1239932D01*
G01X1188388Y1232443D02*
X1189194Y1231178D01*
G01X1188388Y1232443D02*
X1189194Y1231178D01*
G01X1210258Y1294634D02*
X1189838Y1326698D01*
G01X1209419Y1293810D02*
X1189005Y1325865D01*
G01X1359217Y1196034D02*
X1210258Y1294634D01*
G01X1358760Y1194957D02*
X1209419Y1293810D01*
G01D02*
X1189005Y1325865D01*
G01X1210258Y1294634D02*
X1189838Y1326698D01*
G01X1358760Y1194957D02*
X1209419Y1293810D01*
G01X1359217Y1196034D02*
X1210258Y1294634D01*
G01X1198117Y1297473D02*
X1197312Y1298739D01*
G01X1200415Y1293862D02*
X1199610Y1295128D01*
G01X1202932Y1289908D02*
X1201908Y1291517D01*
G01X1198117Y1297473D02*
X1197312Y1298739D01*
G01X1200415Y1293862D02*
X1199610Y1295128D01*
G01X1202932Y1289908D02*
X1201908Y1291517D01*
G01X1267700Y617171D02*
X1398361Y427248D01*
G01X1397543Y426407D02*
X1266625Y616702D01*
G01X1397543Y426407D02*
X1266625Y616702D01*
G01X1267700Y617171D02*
X1398361Y427248D01*
G01X1258150Y617810D02*
X1394284Y419891D01*
G01X1257075Y617342D02*
X1393465Y419050D01*
G01X1257075Y617342D02*
X1393465Y419050D01*
G01X1258150Y617810D02*
X1394284Y419891D01*
G01X1252441Y613774D02*
X1446863Y331131D01*
G01X1446029Y330312D02*
X1251366Y613306D01*
G01X1446029Y330312D02*
X1251366Y613306D01*
G01X1252441Y613774D02*
X1446863Y331131D01*
G01X1502939Y237060D02*
X1245389Y612882D01*
G01X1502186Y236124D02*
X1244314Y612416D01*
G01X1502186Y236124D02*
X1244314Y612416D01*
G01X1502939Y237060D02*
X1245389Y612882D01*
G01X1276350Y641323D02*
X1277804D01*
G01Y640173D02*
X1276236D01*
G01X1274315Y641737D02*
X1276350Y641323D01*
G01X1276236Y640173D02*
X1273867Y640654D01*
G01X1273090Y642547D02*
X1274315Y641737D01*
G01X1273867Y640654D02*
X1272260Y641717D01*
G01X1270354Y646680D02*
X1273090Y642547D01*
G01X1272260Y641717D02*
X1269277Y646223D01*
G01X1272260Y641717D02*
X1269277Y646223D01*
G01X1270354Y646680D02*
X1273090Y642547D01*
G01X1273867Y640654D02*
X1272260Y641717D01*
G01X1273090Y642547D02*
X1274315Y641737D01*
G01X1276236Y640173D02*
X1273867Y640654D01*
G01X1274315Y641737D02*
X1276350Y641323D01*
G01X1277804Y640173D02*
X1276236D01*
G01X1276350Y641323D02*
X1277804D01*
G01X1234330Y1028497D02*
X1247121Y970551D01*
G01X1245943Y970552D02*
X1233207Y1028249D01*
G01X1245943Y970552D02*
X1233207Y1028249D01*
G01X1234330Y1028497D02*
X1247121Y970551D01*
G01X1403396Y841607D02*
X1246784Y1087240D01*
G01X1403396Y841607D02*
X1246784Y1087240D01*
G01X1380872Y863276D02*
X1239438Y1085227D01*
G01X1238359Y1084780D02*
X1379902Y862658D01*
G01X1238359Y1084780D02*
X1379902Y862658D01*
G01X1380872Y863276D02*
X1239438Y1085227D01*
G01X1292003Y1057533D02*
X1268893Y1092441D01*
G01X1291173Y1056703D02*
X1267816Y1091984D01*
G01X1291173Y1056703D02*
X1267816Y1091984D01*
G01X1292003Y1057533D02*
X1268893Y1092441D01*
G01X1267246Y1071368D02*
X1397262Y874919D01*
G01X1266169Y1070911D02*
X1396440Y874075D01*
G01X1253847Y1131817D02*
X1267246Y1071368D01*
G01X1252768Y1131370D02*
X1266169Y1070911D01*
G01D02*
X1396440Y874075D01*
G01X1267246Y1071368D02*
X1397262Y874919D01*
G01X1252768Y1131370D02*
X1266169Y1070911D01*
G01X1253847Y1131817D02*
X1267246Y1071368D01*
G01X1404027Y842757D02*
X1247863Y1087687D01*
G01X1404027Y842757D02*
X1247863Y1087687D01*
G01X1274645Y1095144D02*
X1259886Y1161666D01*
G01X1273625Y1094429D02*
X1258807Y1161219D01*
G01X1276321Y1094079D02*
X1274645Y1095144D01*
G01X1275986Y1092929D02*
X1273625Y1094429D01*
G01X1277804Y1094079D02*
X1276321D01*
G01X1277804Y1092929D02*
X1275986D01*
G01X1273625Y1094429D02*
X1258807Y1161219D01*
G01X1274645Y1095144D02*
X1259886Y1161666D01*
G01X1275986Y1092929D02*
X1273625Y1094429D01*
G01X1276321Y1094079D02*
X1274645Y1095144D01*
G01X1277804Y1092929D02*
X1275986D01*
G01X1277804Y1094079D02*
X1276321D01*
G01X1268893Y1092441D02*
X1258901Y1137512D01*
G01X1267816Y1091984D02*
X1257822Y1137065D01*
G01X1267816Y1091984D02*
X1257822Y1137065D01*
G01X1268893Y1092441D02*
X1258901Y1137512D01*
G01X1247863Y1087687D02*
X1233921Y1150563D01*
G01X1247863Y1087687D02*
X1233921Y1150563D01*
G01X1258807Y1161219D02*
X1247853Y1178412D01*
G01X1258807Y1161219D02*
X1247853Y1178412D01*
G01X1244060Y1184366D02*
X1243254Y1185631D01*
G01X1246360Y1180757D02*
X1245554Y1182022D01*
G01X1244060Y1184366D02*
X1243254Y1185631D01*
G01X1246360Y1180757D02*
X1245554Y1182022D01*
G01X1485754Y929292D02*
X1292003Y1057533D01*
G01X1485119Y928333D02*
X1291173Y1056703D01*
G01X1485119Y928333D02*
X1291173Y1056703D01*
G01X1485754Y929292D02*
X1292003Y1057533D01*
G01X1462405Y1231818D02*
X1316877Y1325493D01*
G01X1369078Y1290523D02*
X1316427Y1324414D01*
G01X1369078Y1290523D02*
X1316427Y1324414D01*
G01X1462405Y1231818D02*
X1316877Y1325493D01*
G01X1462405Y1231818D02*
X1316877Y1325493D01*
G01X1462405Y1231818D02*
X1316877Y1325493D01*
G01X1462405Y1231818D02*
X1316877Y1325493D01*
G01X1466507Y1240237D02*
X1325983Y1329774D01*
G01X1325536Y1328695D02*
X1466068Y1239152D01*
G01X1325536Y1328695D02*
X1466068Y1239152D01*
G01X1325536Y1328695D02*
X1466068Y1239152D01*
G01X1466507Y1240237D02*
X1325983Y1329774D01*
G01X1334527Y917269D02*
X1393988Y649112D01*
G01X1378232Y714855D02*
X1333448Y916822D01*
G01X1378232Y714855D02*
X1333448Y916822D01*
G01X1334527Y917269D02*
X1393988Y649112D01*
G01X1334527Y917269D02*
X1393988Y649112D01*
G01X1369383Y1113140D02*
X1335534Y1164279D01*
G01X1368553Y1112310D02*
X1334705Y1163447D01*
G01X1397392Y1094601D02*
X1369383Y1113140D01*
G01X1396944Y1093518D02*
X1368553Y1112310D01*
G01D02*
X1334705Y1163447D01*
G01X1369383Y1113140D02*
X1335534Y1164279D01*
G01X1396944Y1093518D02*
X1368553Y1112310D01*
G01X1397392Y1094601D02*
X1369383Y1113140D01*
G01X1335339Y1164408D02*
X1335338D01*
G01X1335534Y1164279D02*
X1335339Y1164409D01*
G01Y1164408D02*
X1335338D01*
G01X1335534Y1164279D02*
X1335339Y1164409D01*
G01X1457934Y1174149D02*
X1359217Y1196034D01*
G01X1367287Y1193067D02*
X1358760Y1194957D01*
G01X1371387Y1192158D02*
X1369923Y1192482D01*
G01X1375488Y1191249D02*
X1374023Y1191573D01*
G01X1367287Y1193067D02*
X1358760Y1194957D01*
G01X1457934Y1174149D02*
X1359217Y1196034D01*
G01X1371387Y1192158D02*
X1369923Y1192482D01*
G01X1457934Y1174149D02*
X1359217Y1196034D01*
G01X1375488Y1191249D02*
X1374023Y1191573D01*
G01X1457934Y1174149D02*
X1359217Y1196034D01*
G01X1457934Y1174149D02*
X1359217Y1196034D01*
G01X1372610Y1288250D02*
X1371349Y1289062D01*
G01X1376141Y1285976D02*
X1374880Y1286788D01*
G01X1372610Y1288250D02*
X1371349Y1289062D01*
G01X1376141Y1285976D02*
X1374880Y1286788D01*
G01X1394284Y419891D02*
X1648131Y255052D01*
G01X1393465Y419050D02*
X1647683Y253971D01*
G01X1393465Y419050D02*
X1647683Y253971D01*
G01X1394284Y419891D02*
X1648131Y255052D01*
G01X1398361Y427248D02*
X1649981Y264195D01*
G01X1649534Y263114D02*
X1397543Y426407D01*
G01X1649534Y263114D02*
X1397543Y426407D01*
G01X1398361Y427248D02*
X1649981Y264195D01*
G01X1400758Y641323D02*
X1402017D01*
G01Y640173D02*
X1400631D01*
G01X1399538Y641599D02*
X1400758Y641323D01*
G01X1400631Y640173D02*
X1399092Y640520D01*
G01X1398697Y642128D02*
X1399538Y641599D01*
G01X1399092Y640520D02*
X1397879Y641284D01*
G01X1395165Y647368D02*
X1398697Y642128D01*
G01X1397879Y641284D02*
X1394211Y646724D01*
G01X1395061Y647522D02*
X1395165Y647368D01*
G01X1394211Y646724D02*
X1392912Y648650D01*
G01X1397879Y641284D02*
X1394211Y646724D01*
G01X1393988Y649112D02*
X1395061Y647522D01*
G01X1394211Y646724D02*
X1392912Y648650D01*
G01X1394211Y646724D02*
X1392912Y648650D01*
G01X1395061Y647522D02*
X1395165Y647368D01*
G01X1393988Y649112D02*
X1395061Y647522D01*
G01X1397879Y641284D02*
X1394211Y646724D01*
G01X1395165Y647368D02*
X1398697Y642128D01*
G01X1395061Y647522D02*
X1395165Y647368D01*
G01X1399092Y640520D02*
X1397879Y641284D01*
G01X1398697Y642128D02*
X1399538Y641599D01*
G01X1400631Y640173D02*
X1399092Y640520D01*
G01X1399538Y641599D02*
X1400758Y641323D01*
G01X1402017Y640173D02*
X1400631D01*
G01X1400758Y641323D02*
X1402017D01*
G01X1392912Y648650D02*
X1378232Y714855D01*
G01X1392912Y648650D02*
X1378232Y714855D01*
G01X1521660Y642339D02*
X1380872Y863276D01*
G01X1379902Y862658D02*
X1520829Y641502D01*
G01X1379902Y862658D02*
X1520829Y641502D01*
G01X1521660Y642339D02*
X1380872Y863276D01*
G01X1455390Y762200D02*
X1404028Y842757D01*
G01X1454559Y761362D02*
X1403396Y841607D01*
G01X1454559Y761362D02*
X1403396Y841607D01*
G01X1455390Y762200D02*
X1404028Y842757D01*
G01X1397262Y874919D02*
X1557742Y774618D01*
G01X1396440Y874075D02*
X1557023Y773710D01*
G01X1396440Y874075D02*
X1557023Y773710D01*
G01X1397262Y874919D02*
X1557742Y774618D01*
G01X1399971Y1094079D02*
X1397392Y1094601D01*
G01X1399855Y1092929D02*
X1396944Y1093518D01*
G01X1402017Y1094079D02*
X1399971D01*
G01X1402017Y1092929D02*
X1399855D01*
G01D02*
X1396944Y1093518D01*
G01X1399971Y1094079D02*
X1397392Y1094601D01*
G01X1402017Y1092929D02*
X1399855D01*
G01X1402017Y1094079D02*
X1399971D01*
G01X1414109Y1166710D02*
X1380952Y1173457D01*
G01X1413660Y1165627D02*
X1380503Y1172374D01*
G01X1468929Y1130426D02*
X1414109Y1166710D01*
G01X1523497Y1092929D02*
X1413660Y1165627D01*
G01X1523497Y1092929D02*
X1413660Y1165627D01*
G01X1523497Y1092929D02*
X1413660Y1165627D01*
G01D02*
X1380503Y1172374D01*
G01X1414109Y1166710D02*
X1380952Y1173457D01*
G01X1523497Y1092929D02*
X1413660Y1165627D01*
G01X1468929Y1130426D02*
X1414109Y1166710D01*
G01X1457582Y1173048D02*
X1378124Y1190664D01*
G01X1457582Y1173048D02*
X1378124Y1190664D01*
G01X1461964Y1230734D02*
X1378412Y1284515D01*
G01X1461964Y1230734D02*
X1378412Y1284515D01*
G01X1446863Y331131D02*
X1644884Y189505D01*
G01X1644386Y188447D02*
X1446029Y330312D01*
G01X1644386Y188447D02*
X1446029Y330312D01*
G01X1446863Y331131D02*
X1644884Y189505D01*
G01X1552006Y701814D02*
X1455390Y762200D01*
G01X1648461Y640173D02*
X1454559Y761362D01*
G01X1648461Y640173D02*
X1454559Y761362D01*
G01X1648461Y640173D02*
X1454559Y761362D01*
G01X1552006Y701814D02*
X1455390Y762200D01*
G01X1468928Y1130426D02*
X1468929D01*
G01X1523844Y1094079D02*
X1468928Y1130426D01*
G01D02*
X1468929D01*
G01X1523844Y1094079D02*
X1468928Y1130426D01*
G01X1647300Y1094079D02*
X1457934Y1174149D01*
G01X1647066Y1092929D02*
X1457582Y1173048D01*
G01X1647066Y1092929D02*
X1457582Y1173048D01*
G01X1647300Y1094079D02*
X1457934Y1174149D01*
G01X1466508Y1240237D02*
X1466507D01*
G01X1466068Y1239152D02*
X1467538Y1238853D01*
G01X1777679Y1176925D02*
X1466508Y1240237D01*
G01X1474456Y1237445D02*
X1475926Y1237146D01*
G01X1470262Y1238299D02*
X1471732Y1238000D01*
G01X1466068Y1239152D02*
X1467538Y1238853D01*
G01X1777679Y1176925D02*
X1466508Y1240237D01*
G01X1777679Y1176925D02*
X1466508Y1240237D01*
G01X1474456Y1237445D02*
X1475926Y1237146D01*
G01X1777679Y1176925D02*
X1466508Y1240237D01*
G01X1470262Y1238299D02*
X1471732Y1238000D01*
G01X1777679Y1176925D02*
X1466508Y1240237D01*
G01X1466068Y1239152D02*
X1467538Y1238853D01*
G01X1466508Y1240237D02*
X1466507D01*
G01X1777679Y1176925D02*
X1466508Y1240237D01*
G01D02*
X1466507D01*
G01X1608304Y1202135D02*
X1462405Y1231818D01*
G01X1607855Y1201052D02*
X1461964Y1230734D01*
G01X1607855Y1201052D02*
X1461964Y1230734D01*
G01X1608304Y1202135D02*
X1462405Y1231818D01*
G01X1523561Y189084D02*
X1503057Y237012D01*
G01X1512815Y211276D02*
X1502186Y236124D01*
G01X1522590Y188427D02*
X1512816Y211276D01*
G01X1523028Y187990D02*
X1522590Y188427D01*
G01X1523601Y187417D02*
X1523028Y187990D01*
G01X1512815Y211276D02*
X1502186Y236124D01*
G01X1523561Y189084D02*
X1503057Y237012D01*
G01X1522590Y188427D02*
X1512816Y211276D01*
G01X1523561Y189084D02*
X1503057Y237012D01*
G01X1523028Y187990D02*
X1522590Y188427D01*
G01X1523601Y187417D02*
X1523028Y187990D01*
G01X1523279Y641323D02*
X1521660Y642339D01*
G01X1520829Y641502D02*
X1522948Y640173D01*
G01D02*
X1526229D01*
G01X1522948D02*
X1526229D01*
G01X1520829Y641502D02*
X1522948Y640173D01*
G01X1523279Y641323D02*
X1521660Y642339D01*
G01X1487461Y928161D02*
X1485754Y929292D01*
G01X1487004Y927084D02*
X1485119Y928333D01*
G01X1694100Y887002D02*
X1487461Y928161D01*
G01X1693609Y885927D02*
X1487015Y927077D01*
G01X1487004Y927084D02*
X1485119Y928333D01*
G01X1487461Y928161D02*
X1485754Y929292D01*
G01X1693609Y885927D02*
X1487015Y927077D01*
G01X1694100Y887002D02*
X1487461Y928161D01*
G01X1478650Y1236592D02*
X1621652Y1207497D01*
G01X1478650Y1236592D02*
X1621652Y1207497D01*
G01X1524078Y188567D02*
X1523561Y189084D01*
G01X1526229Y188567D02*
X1524078D01*
G01X1526229Y187417D02*
X1523601D01*
G01X1524078Y188567D02*
X1523561Y189084D01*
G01X1524078Y188567D02*
X1523561Y189084D01*
G01X1526229Y187417D02*
X1523601D01*
G01X1526229Y188567D02*
X1524078D01*
G01X1526229Y641323D02*
X1523279D01*
G01X1526229D02*
X1523279D01*
G01X1648791D02*
X1552006Y701815D01*
G01X1648791Y641323D02*
X1552006Y701815D01*
G01X1557742Y774618D02*
X1665085Y668260D01*
G01X1557023Y773710D02*
X1664410Y667309D01*
G01X1557023Y773710D02*
X1664410Y667309D01*
G01X1557742Y774618D02*
X1665085Y668260D01*
G01X1526229Y1094079D02*
X1523844D01*
G01X1526229Y1092929D02*
X1523497D01*
G01X1526229D02*
X1523497D01*
G01X1526229Y1094079D02*
X1523844D01*
G01X1771554D02*
X1608304Y1202135D01*
G01X1771207Y1092929D02*
X1607855Y1201052D01*
G01X1771207Y1092929D02*
X1607855Y1201052D01*
G01X1771554Y1094079D02*
X1608304Y1202135D01*
G01X1648422Y188567D02*
X1650442D01*
G01Y187417D02*
X1648272D01*
G01X1646515Y189073D02*
X1648422Y188567D01*
G01X1646807Y187805D02*
X1644386Y188447D01*
G01X1648272Y187417D02*
X1646807Y187805D01*
G01X1644884Y189505D02*
X1646515Y189073D01*
G01X1646807Y187805D02*
X1644386Y188447D01*
G01X1646807Y187805D02*
X1644386Y188447D01*
G01X1646515Y189073D02*
X1648422Y188567D01*
G01X1644884Y189505D02*
X1646515Y189073D01*
G01X1648272Y187417D02*
X1646807Y187805D01*
G01X1646515Y189073D02*
X1648422Y188567D01*
G01X1650442Y187417D02*
X1648272D01*
G01X1648422Y188567D02*
X1650442D01*
G01X1649981Y264195D02*
X1697055Y254192D01*
G01X1696691Y253093D02*
X1649534Y263114D01*
G01X1696691Y253093D02*
X1649534Y263114D01*
G01X1649981Y264195D02*
X1697055Y254192D01*
G01X1648131Y255052D02*
X1690537Y246037D01*
G01X1658382Y251697D02*
X1690063Y244962D01*
G01X1647683Y253971D02*
X1658382Y251697D01*
G01D02*
X1690063Y244962D01*
G01X1648131Y255052D02*
X1690537Y246037D01*
G01X1647683Y253971D02*
X1658382Y251697D01*
G01X1648131Y255052D02*
X1690537Y246037D01*
G01X1650442Y641323D02*
X1648791D01*
G01X1650442Y640173D02*
X1648461D01*
G01X1650442D02*
X1648461D01*
G01X1650442Y641323D02*
X1648791D01*
G01X1665085Y668260D02*
X1720282Y641323D01*
G01X1664410Y667309D02*
X1720016Y640173D01*
G01X1664410Y667309D02*
X1720016Y640173D01*
G01X1665085Y668260D02*
X1720282Y641323D01*
G01X1650442Y1094079D02*
X1647300D01*
G01X1650442Y1092929D02*
X1647066D01*
G01X1650442D02*
X1647066D01*
G01X1650442Y1094079D02*
X1647300D01*
G01X1621652Y1207497D02*
X1777230Y1175842D01*
G01X1621652Y1207497D02*
X1777230Y1175842D01*
G01X1697055Y254190D02*
X1825597Y195169D01*
G01X1825293Y194043D02*
X1696691Y253091D01*
G01X1825293Y194043D02*
X1696691Y253091D01*
G01X1697055Y254190D02*
X1825597Y195169D01*
G01X1690537Y246037D02*
X1769675Y189434D01*
G01X1690063Y244962D02*
X1769179Y188374D01*
G01X1690063Y244962D02*
X1769179Y188374D01*
G01X1690537Y246037D02*
X1769675Y189434D01*
G01X1720099Y866825D02*
X1694100Y887002D01*
G01X1719269Y866013D02*
X1693609Y885927D01*
G01X1719269Y866013D02*
X1693609Y885927D01*
G01X1720099Y866825D02*
X1694100Y887002D01*
G01X1720282Y641323D02*
X1724654D01*
G01X1720016Y640173D02*
X1724654D01*
G01X1720016D02*
X1724654D01*
G01X1720282Y641323D02*
X1724654D01*
G01X1773961Y794162D02*
X1720099Y866825D01*
G01X1746153Y829745D02*
X1719269Y866013D01*
G01X1773132Y793349D02*
X1746153Y829745D01*
G01D02*
X1719269Y866013D01*
G01X1773961Y794162D02*
X1720099Y866825D01*
G01X1773132Y793349D02*
X1746153Y829745D01*
G01X1773961Y794162D02*
X1720099Y866825D01*
G01X1772938Y188567D02*
X1774654D01*
G01X1772787Y187417D02*
X1774654D01*
G01X1769675Y189434D02*
X1772938Y188567D01*
G01X1769179Y188374D02*
X1772787Y187417D01*
G01D02*
X1774654D01*
G01X1772938Y188567D02*
X1774654D01*
G01X1769179Y188374D02*
X1772787Y187417D01*
G01X1769675Y189434D02*
X1772938Y188567D01*
G01X1817811Y760329D02*
X1773961Y794162D01*
G01X1816957Y759535D02*
X1773132Y793349D01*
G01X1816957Y759535D02*
X1773132Y793349D01*
G01X1817811Y760329D02*
X1773961Y794162D01*
G01X1774654Y1094079D02*
X1771554D01*
G01X1774654Y1092929D02*
X1771207D01*
G01X1774654D02*
X1771207D01*
G01X1774654Y1094079D02*
X1771554D01*
G01X1883379Y1106962D02*
X1777679Y1176925D01*
G01X1783808Y1171489D02*
X1833178Y1138811D01*
G01X1783807Y1171489D02*
X1783808D01*
G01X1777230Y1175842D02*
X1783807Y1171489D01*
G01X1883379Y1106962D02*
X1777679Y1176925D01*
G01X1783808Y1171489D02*
X1833178Y1138811D01*
G01X1883379Y1106962D02*
X1777679Y1176925D01*
G01X1783807Y1171489D02*
X1783808D01*
G01X1883379Y1106962D02*
X1777679Y1176925D01*
G01X1777230Y1175842D02*
X1783807Y1171489D01*
G01X1883379Y1106962D02*
X1777679Y1176925D01*
G01X1859077Y191919D02*
X1893600Y188567D01*
G01X1893544Y187417D02*
X1825293Y194043D01*
G01X1859078Y191919D02*
X1859077D01*
G01X1893544Y187417D02*
X1825293Y194043D01*
G01X1825597Y195169D02*
X1859078Y191919D01*
G01X1893544Y187417D02*
X1825293Y194043D01*
G01X1893544Y187417D02*
X1825293Y194043D01*
G01X1859077Y191919D02*
X1893600Y188567D01*
G01X1859078Y191919D02*
X1859077D01*
G01X1825597Y195169D02*
X1859078Y191919D01*
G01X1895587Y642713D02*
X1817811Y760329D01*
G01X1894691Y641982D02*
X1816957Y759535D01*
G01X1894691Y641982D02*
X1816957Y759535D01*
G01X1895587Y642713D02*
X1817811Y760329D01*
G01X1833178Y1138811D02*
X1882549Y1106132D01*
G01X1833178Y1138811D02*
X1882549Y1106132D01*
G01X1893600Y188567D02*
X1898867D01*
G01Y187417D02*
X1893544D01*
G01X1898867D02*
X1893544D01*
G01X1893600Y188567D02*
X1898867D01*
G01X1896897Y641400D02*
X1895587Y642713D01*
G01X1895427Y641244D02*
X1894691Y641982D01*
G01X1896082Y640588D02*
X1895427Y641244D01*
G01X1896419Y640250D02*
X1896082Y640588D01*
G01X1896974Y641323D02*
X1896897Y641400D01*
G01X1896082Y640588D02*
X1895427Y641244D01*
G01X1896419Y640250D02*
X1896082Y640588D01*
G01X1898867Y641323D02*
X1896974D01*
G01X1898867Y640173D02*
X1896496D01*
G01X1895427Y641244D02*
X1894691Y641982D01*
G01X1896897Y641400D02*
X1895587Y642713D01*
G01X1896082Y640588D02*
X1895427Y641244D01*
G01X1896897Y641400D02*
X1895587Y642713D01*
G01X1896974Y641323D02*
X1896897Y641400D01*
G01X1896419Y640250D02*
X1896082Y640588D01*
G01X1896897Y641400D02*
X1895587Y642713D01*
G01X1896974Y641323D02*
X1896897Y641400D01*
G01X1898867Y640173D02*
X1896496D01*
G01X1898867Y641323D02*
X1896974D01*
G01X1889378Y1097903D02*
X1883379Y1106962D01*
G01X1882549Y1106132D02*
X1888548Y1097073D01*
G01X1894367Y1094601D02*
X1889378Y1097903D01*
G01X1888548Y1097073D02*
X1893918Y1093518D01*
G01X1896558Y1094079D02*
X1894367Y1094601D01*
G01X1894101Y1093482D02*
X1896422Y1092929D01*
G01X1893918Y1093518D02*
X1894101Y1093482D01*
G01X1898867Y1094079D02*
X1896558D01*
G01X1896422Y1092929D02*
X1898867D01*
G01X1896422D02*
X1898867D01*
G01Y1094079D02*
X1896558D01*
G01X1894101Y1093482D02*
X1896422Y1092929D01*
G01X1896558Y1094079D02*
X1894367Y1094601D01*
G01X1893918Y1093518D02*
X1894101Y1093482D01*
G01X1896558Y1094079D02*
X1894367Y1094601D01*
G01X1888548Y1097073D02*
X1893918Y1093518D01*
G01X1894367Y1094601D02*
X1889378Y1097903D01*
G01X1882549Y1106132D02*
X1888548Y1097073D01*
G01X1889378Y1097903D02*
X1883379Y1106962D01*
G54D12*
G01X6250Y-185556D02*
Y-203056D01*
G01X1228Y-185556D02*
X11272D01*
G01X20038Y-203056D02*
Y-185556D01*
G01Y-194014D02*
X21130Y-192556D01*
X22222Y-191681D01*
X23968Y-191390D01*
X25278Y-191681D01*
X26807Y-192848D01*
X27462Y-194598D01*
Y-203056D01*
G01X41250Y-191390D02*
Y-203056D01*
G01Y-186723D02*
X40813Y-186431D01*
Y-185848D01*
X41250Y-185556D01*
X41687Y-185848D01*
Y-186431D01*
X41250Y-186723D01*
G01X55475Y-201015D02*
X56567Y-202181D01*
X58095Y-203056D01*
X59405D01*
X60715Y-202473D01*
X61588Y-201598D01*
X62025Y-200432D01*
X61807Y-198681D01*
X60933Y-197806D01*
X57003Y-196056D01*
X56130Y-194014D01*
X56567Y-192556D01*
X57440Y-191681D01*
X58750Y-191390D01*
X60060Y-191681D01*
X61370Y-192556D01*
G01X90693Y-207431D02*
X92222Y-208598D01*
X93968Y-208889D01*
X95496Y-208598D01*
X96807Y-207140D01*
X97680Y-205098D01*
Y-191390D01*
G01Y-193723D02*
X96807Y-192556D01*
X95496Y-191681D01*
X93968Y-191390D01*
X92222Y-191973D01*
X91130Y-193139D01*
X90256Y-195181D01*
X89820Y-197223D01*
X90038Y-198973D01*
X90912Y-201015D01*
X92222Y-202473D01*
X93968Y-203056D01*
X95278Y-202764D01*
X96807Y-201598D01*
X97680Y-200432D01*
G01X107975Y-195181D02*
X114962D01*
X114307Y-193139D01*
X113215Y-191973D01*
X111687Y-191390D01*
X110158Y-191681D01*
X108848Y-192556D01*
X107975Y-194598D01*
X107538Y-196348D01*
Y-198098D01*
X107975Y-199848D01*
X109067Y-201598D01*
X110377Y-202764D01*
X111905Y-203056D01*
X113433Y-202473D01*
X114962Y-200723D01*
G01X125693Y-203056D02*
Y-191390D01*
G01Y-193723D02*
X126785Y-192556D01*
X127877Y-191681D01*
X129405Y-191390D01*
X130496Y-191681D01*
X131807Y-192556D01*
G01X142320Y-203056D02*
Y-185556D01*
G01Y-194306D02*
X143412Y-192556D01*
X144722Y-191681D01*
X146032Y-191390D01*
X147996Y-191973D01*
X149307Y-193139D01*
X150180Y-195181D01*
Y-197514D01*
X149743Y-199848D01*
X148870Y-201598D01*
X147342Y-202764D01*
X146032Y-203056D01*
X144722Y-202764D01*
X143412Y-201890D01*
X142320Y-200432D01*
G01X160475Y-195181D02*
X167462D01*
X166807Y-193139D01*
X165715Y-191973D01*
X164187Y-191390D01*
X162658Y-191681D01*
X161348Y-192556D01*
X160475Y-194598D01*
X160038Y-196348D01*
Y-198098D01*
X160475Y-199848D01*
X161567Y-201598D01*
X162877Y-202764D01*
X164405Y-203056D01*
X165933Y-202473D01*
X167462Y-200723D01*
G01X178193Y-203056D02*
Y-191390D01*
G01Y-193723D02*
X179285Y-192556D01*
X180377Y-191681D01*
X181905Y-191390D01*
X182996Y-191681D01*
X184307Y-192556D01*
G01X216250Y-191390D02*
Y-203056D01*
G01Y-186723D02*
X215813Y-186431D01*
Y-185848D01*
X216250Y-185556D01*
X216687Y-185848D01*
Y-186431D01*
X216250Y-186723D01*
G01X230475Y-201015D02*
X231567Y-202181D01*
X233095Y-203056D01*
X234405D01*
X235715Y-202473D01*
X236588Y-201598D01*
X237025Y-200432D01*
X236807Y-198681D01*
X235933Y-197806D01*
X232003Y-196056D01*
X231130Y-194014D01*
X231567Y-192556D01*
X232440Y-191681D01*
X233750Y-191390D01*
X235060Y-191681D01*
X236370Y-192556D01*
G01X265256Y-207431D02*
X266785Y-208598D01*
X268095Y-208889D01*
X269842Y-208306D01*
X271152Y-206848D01*
X271807Y-204222D01*
Y-191390D01*
G01Y-186723D02*
X271370Y-186431D01*
Y-185848D01*
X271807Y-185556D01*
X272243Y-185848D01*
Y-186431D01*
X271807Y-186723D01*
G01X282538Y-191390D02*
Y-199556D01*
X283412Y-201598D01*
X284722Y-202764D01*
X286250Y-203056D01*
X287778Y-202764D01*
X289088Y-201598D01*
X289962Y-199556D01*
G01Y-203056D02*
Y-191390D01*
G01X300475Y-201015D02*
X301567Y-202181D01*
X303095Y-203056D01*
X304405D01*
X305715Y-202473D01*
X306588Y-201598D01*
X307025Y-200432D01*
X306807Y-198681D01*
X305933Y-197806D01*
X302003Y-196056D01*
X301130Y-194014D01*
X301567Y-192556D01*
X302440Y-191681D01*
X303750Y-191390D01*
X305060Y-191681D01*
X306370Y-192556D01*
G01X321250Y-185556D02*
Y-203056D01*
G01X318193Y-191390D02*
X324307D01*
G01X354940Y-203056D02*
Y-188181D01*
X355377Y-186723D01*
X356250Y-185848D01*
X357560Y-185556D01*
X358870Y-186139D01*
X359525Y-187598D01*
G01X356905Y-192556D02*
X352538D01*
G01X373750Y-203056D02*
X372440Y-202764D01*
X371130Y-201598D01*
X370256Y-199556D01*
X369820Y-197223D01*
X370256Y-194889D01*
X371130Y-192848D01*
X372440Y-191681D01*
X373750Y-191390D01*
X375060Y-191681D01*
X376370Y-192848D01*
X377243Y-194889D01*
X377462Y-197223D01*
X377243Y-199556D01*
X376370Y-201598D01*
X375060Y-202764D01*
X373750Y-203056D01*
G01X388193D02*
Y-191390D01*
G01Y-193723D02*
X389285Y-192556D01*
X390377Y-191681D01*
X391905Y-191390D01*
X392996Y-191681D01*
X394307Y-192556D01*
G01X421665Y-208306D02*
X422975Y-208889D01*
X424722Y-208306D01*
X425813Y-207140D01*
X426687Y-205681D01*
X427996Y-201015D01*
X430835Y-191390D01*
G01X423848D02*
X427996Y-201015D01*
G01X443750Y-203056D02*
X442440Y-202764D01*
X441130Y-201598D01*
X440256Y-199556D01*
X439820Y-197223D01*
X440256Y-194889D01*
X441130Y-192848D01*
X442440Y-191681D01*
X443750Y-191390D01*
X445060Y-191681D01*
X446370Y-192848D01*
X447243Y-194889D01*
X447462Y-197223D01*
X447243Y-199556D01*
X446370Y-201598D01*
X445060Y-202764D01*
X443750Y-203056D01*
G01X457538Y-191390D02*
Y-199556D01*
X458412Y-201598D01*
X459722Y-202764D01*
X461250Y-203056D01*
X462778Y-202764D01*
X464088Y-201598D01*
X464962Y-199556D01*
G01Y-203056D02*
Y-191390D01*
G01X475693Y-203056D02*
Y-191390D01*
G01Y-193723D02*
X476785Y-192556D01*
X477877Y-191681D01*
X479405Y-191390D01*
X480496Y-191681D01*
X481807Y-192556D01*
G01X510693Y-203056D02*
Y-191390D01*
G01Y-193723D02*
X511785Y-192556D01*
X512877Y-191681D01*
X514405Y-191390D01*
X515496Y-191681D01*
X516807Y-192556D01*
G01X527975Y-195181D02*
X534962D01*
X534307Y-193139D01*
X533215Y-191973D01*
X531687Y-191390D01*
X530158Y-191681D01*
X528848Y-192556D01*
X527975Y-194598D01*
X527538Y-196348D01*
Y-198098D01*
X527975Y-199848D01*
X529067Y-201598D01*
X530377Y-202764D01*
X531905Y-203056D01*
X533433Y-202473D01*
X534962Y-200723D01*
G01X547440Y-203056D02*
Y-188181D01*
X547877Y-186723D01*
X548750Y-185848D01*
X550060Y-185556D01*
X551370Y-186139D01*
X552025Y-187598D01*
G01X549405Y-192556D02*
X545038D01*
G01X562975Y-195181D02*
X569962D01*
X569307Y-193139D01*
X568215Y-191973D01*
X566687Y-191390D01*
X565158Y-191681D01*
X563848Y-192556D01*
X562975Y-194598D01*
X562538Y-196348D01*
Y-198098D01*
X562975Y-199848D01*
X564067Y-201598D01*
X565377Y-202764D01*
X566905Y-203056D01*
X568433Y-202473D01*
X569962Y-200723D01*
G01X580693Y-203056D02*
Y-191390D01*
G01Y-193723D02*
X581785Y-192556D01*
X582877Y-191681D01*
X584405Y-191390D01*
X585496Y-191681D01*
X586807Y-192556D01*
G01X597975Y-195181D02*
X604962D01*
X604307Y-193139D01*
X603215Y-191973D01*
X601687Y-191390D01*
X600158Y-191681D01*
X598848Y-192556D01*
X597975Y-194598D01*
X597538Y-196348D01*
Y-198098D01*
X597975Y-199848D01*
X599067Y-201598D01*
X600377Y-202764D01*
X601905Y-203056D01*
X603433Y-202473D01*
X604962Y-200723D01*
G01X615038Y-203056D02*
Y-191390D01*
G01Y-194306D02*
X615912Y-192848D01*
X617222Y-191681D01*
X618968Y-191390D01*
X620496Y-191681D01*
X621807Y-192848D01*
X622462Y-194889D01*
Y-203056D01*
G01X639743Y-192848D02*
X638215Y-191681D01*
X636905Y-191390D01*
X635158Y-191973D01*
X633848Y-193139D01*
X632975Y-195181D01*
X632756Y-197223D01*
X632975Y-199265D01*
X633848Y-201015D01*
X635158Y-202473D01*
X636905Y-203056D01*
X638433Y-202473D01*
X639743Y-201306D01*
G01X650475Y-195181D02*
X657462D01*
X656807Y-193139D01*
X655715Y-191973D01*
X654187Y-191390D01*
X652658Y-191681D01*
X651348Y-192556D01*
X650475Y-194598D01*
X650038Y-196348D01*
Y-198098D01*
X650475Y-199848D01*
X651567Y-201598D01*
X652877Y-202764D01*
X654405Y-203056D01*
X655933Y-202473D01*
X657462Y-200723D01*
G01X688750Y-185556D02*
Y-203056D01*
G01X685693Y-191390D02*
X691807D01*
G01X706250Y-203056D02*
X704940Y-202764D01*
X703630Y-201598D01*
X702756Y-199556D01*
X702320Y-197223D01*
X702756Y-194889D01*
X703630Y-192848D01*
X704940Y-191681D01*
X706250Y-191390D01*
X707560Y-191681D01*
X708870Y-192848D01*
X709743Y-194889D01*
X709962Y-197223D01*
X709743Y-199556D01*
X708870Y-201598D01*
X707560Y-202764D01*
X706250Y-203056D01*
G01X739940D02*
Y-188181D01*
X740377Y-186723D01*
X741250Y-185848D01*
X742560Y-185556D01*
X743870Y-186139D01*
X744525Y-187598D01*
G01X741905Y-192556D02*
X737538D01*
G01X758750Y-191390D02*
Y-203056D01*
G01Y-186723D02*
X758313Y-186431D01*
Y-185848D01*
X758750Y-185556D01*
X759187Y-185848D01*
Y-186431D01*
X758750Y-186723D01*
G01X772538Y-203056D02*
Y-191390D01*
G01Y-194306D02*
X773412Y-192848D01*
X774722Y-191681D01*
X776468Y-191390D01*
X777996Y-191681D01*
X779307Y-192848D01*
X779962Y-194889D01*
Y-203056D01*
G01X797680Y-185556D02*
Y-203056D01*
G01Y-200432D02*
X796807Y-201890D01*
X795496Y-202764D01*
X793968Y-203056D01*
X792222Y-202473D01*
X790912Y-201015D01*
X790038Y-199265D01*
X789820Y-197223D01*
X790038Y-195181D01*
X790912Y-193431D01*
X792222Y-191973D01*
X793968Y-191390D01*
X795496Y-191681D01*
X796588Y-192265D01*
X797680Y-193431D01*
G01X828750Y-185556D02*
Y-203056D01*
G01X825693Y-191390D02*
X831807D01*
G01X842538Y-203056D02*
Y-185556D01*
G01Y-194014D02*
X843630Y-192556D01*
X844722Y-191681D01*
X846468Y-191390D01*
X847778Y-191681D01*
X849307Y-192848D01*
X849962Y-194598D01*
Y-203056D01*
G01X860475Y-195181D02*
X867462D01*
X866807Y-193139D01*
X865715Y-191973D01*
X864187Y-191390D01*
X862658Y-191681D01*
X861348Y-192556D01*
X860475Y-194598D01*
X860038Y-196348D01*
Y-198098D01*
X860475Y-199848D01*
X861567Y-201598D01*
X862877Y-202764D01*
X864405Y-203056D01*
X865933Y-202473D01*
X867462Y-200723D01*
G01X893947Y-203056D02*
Y-185556D01*
X898313D01*
X900060Y-186431D01*
X901370Y-187598D01*
X902462Y-189347D01*
X903335Y-191390D01*
X903553Y-194306D01*
X903335Y-197223D01*
X902462Y-199265D01*
X901370Y-201015D01*
X900060Y-202181D01*
X898313Y-203056D01*
X893947D01*
G01X911883D02*
Y-185556D01*
X917123D01*
X918870Y-186431D01*
X920180Y-188473D01*
X920617Y-190806D01*
X920180Y-193139D01*
X919088Y-194889D01*
X917123Y-195765D01*
X911883D01*
G01X951250Y-191390D02*
Y-203056D01*
G01Y-186723D02*
X950813Y-186431D01*
Y-185848D01*
X951250Y-185556D01*
X951687Y-185848D01*
Y-186431D01*
X951250Y-186723D01*
G01X962200Y-203056D02*
Y-191390D01*
G01Y-194598D02*
X962855Y-193139D01*
X963947Y-191973D01*
X965475Y-191390D01*
X967003Y-191973D01*
X968095Y-193139D01*
X968750Y-194598D01*
Y-203056D01*
G01Y-194598D02*
X969405Y-193139D01*
X970496Y-191973D01*
X972025Y-191390D01*
X973553Y-191973D01*
X974645Y-193139D01*
X975300Y-194889D01*
Y-203056D01*
G01X982320Y-208889D02*
Y-191390D01*
G01Y-194014D02*
X983412Y-192556D01*
X984503Y-191681D01*
X986250Y-191390D01*
X987778Y-191681D01*
X989307Y-193139D01*
X989962Y-195181D01*
X990180Y-197223D01*
X989962Y-199265D01*
X989307Y-201306D01*
X987996Y-202473D01*
X986250Y-203056D01*
X984722Y-202764D01*
X983193Y-201890D01*
X982320Y-200723D01*
G01X1000475Y-195181D02*
X1007462D01*
X1006807Y-193139D01*
X1005715Y-191973D01*
X1004187Y-191390D01*
X1002658Y-191681D01*
X1001348Y-192556D01*
X1000475Y-194598D01*
X1000038Y-196348D01*
Y-198098D01*
X1000475Y-199848D01*
X1001567Y-201598D01*
X1002877Y-202764D01*
X1004405Y-203056D01*
X1005933Y-202473D01*
X1007462Y-200723D01*
G01X1025180Y-185556D02*
Y-203056D01*
G01Y-200432D02*
X1024307Y-201890D01*
X1022996Y-202764D01*
X1021468Y-203056D01*
X1019722Y-202473D01*
X1018412Y-201015D01*
X1017538Y-199265D01*
X1017320Y-197223D01*
X1017538Y-195181D01*
X1018412Y-193431D01*
X1019722Y-191973D01*
X1021468Y-191390D01*
X1022996Y-191681D01*
X1024088Y-192265D01*
X1025180Y-193431D01*
G01X1042680Y-203056D02*
Y-191390D01*
G01Y-193431D02*
X1041807Y-192265D01*
X1040496Y-191681D01*
X1038968Y-191390D01*
X1037440Y-191973D01*
X1036130Y-193139D01*
X1035256Y-194889D01*
X1034820Y-197223D01*
X1035256Y-199556D01*
X1036130Y-201306D01*
X1037440Y-202473D01*
X1038968Y-203056D01*
X1040496Y-202764D01*
X1041807Y-201890D01*
X1042680Y-200723D01*
G01X1052538Y-203056D02*
Y-191390D01*
G01Y-194306D02*
X1053412Y-192848D01*
X1054722Y-191681D01*
X1056468Y-191390D01*
X1057996Y-191681D01*
X1059307Y-192848D01*
X1059962Y-194889D01*
Y-203056D01*
G01X1077243Y-192848D02*
X1075715Y-191681D01*
X1074405Y-191390D01*
X1072658Y-191973D01*
X1071348Y-193139D01*
X1070475Y-195181D01*
X1070256Y-197223D01*
X1070475Y-199265D01*
X1071348Y-201015D01*
X1072658Y-202473D01*
X1074405Y-203056D01*
X1075933Y-202473D01*
X1077243Y-201306D01*
G01X1087975Y-195181D02*
X1094962D01*
X1094307Y-193139D01*
X1093215Y-191973D01*
X1091687Y-191390D01*
X1090158Y-191681D01*
X1088848Y-192556D01*
X1087975Y-194598D01*
X1087538Y-196348D01*
Y-198098D01*
X1087975Y-199848D01*
X1089067Y-201598D01*
X1090377Y-202764D01*
X1091905Y-203056D01*
X1093433Y-202473D01*
X1094962Y-200723D01*
G01X1126250Y-185556D02*
Y-203056D01*
G01X1123193Y-191390D02*
X1129307D01*
G01X1140693Y-203056D02*
Y-191390D01*
G01Y-193723D02*
X1141785Y-192556D01*
X1142877Y-191681D01*
X1144405Y-191390D01*
X1145496Y-191681D01*
X1146807Y-192556D01*
G01X1165180Y-203056D02*
Y-191390D01*
G01Y-193431D02*
X1164307Y-192265D01*
X1162996Y-191681D01*
X1161468Y-191390D01*
X1159940Y-191973D01*
X1158630Y-193139D01*
X1157756Y-194889D01*
X1157320Y-197223D01*
X1157756Y-199556D01*
X1158630Y-201306D01*
X1159940Y-202473D01*
X1161468Y-203056D01*
X1162996Y-202764D01*
X1164307Y-201890D01*
X1165180Y-200723D01*
G01X1182243Y-192848D02*
X1180715Y-191681D01*
X1179405Y-191390D01*
X1177658Y-191973D01*
X1176348Y-193139D01*
X1175475Y-195181D01*
X1175256Y-197223D01*
X1175475Y-199265D01*
X1176348Y-201015D01*
X1177658Y-202473D01*
X1179405Y-203056D01*
X1180933Y-202473D01*
X1182243Y-201306D01*
G01X1192975Y-195181D02*
X1199962D01*
X1199307Y-193139D01*
X1198215Y-191973D01*
X1196687Y-191390D01*
X1195158Y-191681D01*
X1193848Y-192556D01*
X1192975Y-194598D01*
X1192538Y-196348D01*
Y-198098D01*
X1192975Y-199848D01*
X1194067Y-201598D01*
X1195377Y-202764D01*
X1196905Y-203056D01*
X1198433Y-202473D01*
X1199962Y-200723D01*
G01X1210475Y-201015D02*
X1211567Y-202181D01*
X1213095Y-203056D01*
X1214405D01*
X1215715Y-202473D01*
X1216588Y-201598D01*
X1217025Y-200432D01*
X1216807Y-198681D01*
X1215933Y-197806D01*
X1212003Y-196056D01*
X1211130Y-194014D01*
X1211567Y-192556D01*
X1212440Y-191681D01*
X1213750Y-191390D01*
X1215060Y-191681D01*
X1216370Y-192556D01*
G01X1248750Y-191390D02*
Y-203056D01*
G01Y-186723D02*
X1248313Y-186431D01*
Y-185848D01*
X1248750Y-185556D01*
X1249187Y-185848D01*
Y-186431D01*
X1248750Y-186723D01*
G01X1262538Y-203056D02*
Y-191390D01*
G01Y-194306D02*
X1263412Y-192848D01*
X1264722Y-191681D01*
X1266468Y-191390D01*
X1267996Y-191681D01*
X1269307Y-192848D01*
X1269962Y-194889D01*
Y-203056D01*
G01X1301250D02*
Y-185556D01*
G01X1322680Y-203056D02*
Y-191390D01*
G01Y-193431D02*
X1321807Y-192265D01*
X1320496Y-191681D01*
X1318968Y-191390D01*
X1317440Y-191973D01*
X1316130Y-193139D01*
X1315256Y-194889D01*
X1314820Y-197223D01*
X1315256Y-199556D01*
X1316130Y-201306D01*
X1317440Y-202473D01*
X1318968Y-203056D01*
X1320496Y-202764D01*
X1321807Y-201890D01*
X1322680Y-200723D01*
G01X1331665Y-208306D02*
X1332975Y-208889D01*
X1334722Y-208306D01*
X1335813Y-207140D01*
X1336687Y-205681D01*
X1337996Y-201015D01*
X1340835Y-191390D01*
G01X1333848D02*
X1337996Y-201015D01*
G01X1350475Y-195181D02*
X1357462D01*
X1356807Y-193139D01*
X1355715Y-191973D01*
X1354187Y-191390D01*
X1352658Y-191681D01*
X1351348Y-192556D01*
X1350475Y-194598D01*
X1350038Y-196348D01*
Y-198098D01*
X1350475Y-199848D01*
X1351567Y-201598D01*
X1352877Y-202764D01*
X1354405Y-203056D01*
X1355933Y-202473D01*
X1357462Y-200723D01*
G01X1368193Y-203056D02*
Y-191390D01*
G01Y-193723D02*
X1369285Y-192556D01*
X1370377Y-191681D01*
X1371905Y-191390D01*
X1372996Y-191681D01*
X1374307Y-192556D01*
G01X1401883Y-185556D02*
Y-203056D01*
X1410617D01*
G01X1423750D02*
Y-185556D01*
X1421130Y-189056D01*
G01Y-203056D02*
X1426370D01*
G01X1437102Y-188473D02*
X1438412Y-186723D01*
X1439940Y-185848D01*
X1441687Y-185556D01*
X1443870Y-186139D01*
X1445398Y-187598D01*
X1445835Y-189347D01*
X1445617Y-191098D01*
X1444743Y-192556D01*
X1440377Y-195473D01*
X1438412Y-197514D01*
X1437102Y-200432D01*
X1436665Y-203056D01*
X1445835D01*
G01X1458750Y-203639D02*
X1458313Y-203348D01*
Y-202764D01*
X1458750Y-202473D01*
X1459187Y-202764D01*
Y-203348D01*
X1458750Y-203639D01*
G01X2008773Y1616518D02*
X2014013D01*
G01X2011393D02*
Y1599018D01*
G01X2008773D02*
X2014013D01*
G01X2023216D02*
Y1616518D01*
X2028893Y1601935D01*
X2034570Y1616518D01*
Y1599018D01*
G01X2042026D02*
Y1616518D01*
X2047266D01*
X2049013Y1615643D01*
X2050323Y1613601D01*
X2050760Y1611268D01*
X2050323Y1608935D01*
X2049231Y1607185D01*
X2047266Y1606309D01*
X2042026D01*
G01X2062801Y1593185D02*
X2060618Y1596101D01*
X2059526Y1599018D01*
Y1610684D01*
X2060618Y1613601D01*
X2062801Y1616518D01*
G01X2081393Y1599018D02*
X2079646Y1599310D01*
X2078118Y1600476D01*
X2076808Y1602226D01*
X2075934Y1604268D01*
X2075498Y1606601D01*
Y1608935D01*
X2075934Y1611268D01*
X2076808Y1613310D01*
X2078118Y1615059D01*
X2079646Y1616226D01*
X2081393Y1616518D01*
X2083139Y1616226D01*
X2084668Y1615059D01*
X2085978Y1613310D01*
X2086852Y1611268D01*
X2087288Y1608935D01*
Y1606601D01*
X2086852Y1604268D01*
X2085978Y1602226D01*
X2084668Y1600476D01*
X2083139Y1599310D01*
X2081393Y1599018D01*
G01X2095181D02*
Y1616518D01*
G01Y1608060D02*
X2096273Y1609518D01*
X2097365Y1610393D01*
X2099111Y1610684D01*
X2100421Y1610393D01*
X2101950Y1609226D01*
X2102605Y1607476D01*
Y1599018D01*
G01X2109843D02*
Y1610684D01*
G01Y1607476D02*
X2110498Y1608935D01*
X2111590Y1610101D01*
X2113118Y1610684D01*
X2114646Y1610101D01*
X2115738Y1608935D01*
X2116393Y1607476D01*
Y1599018D01*
G01Y1607476D02*
X2117048Y1608935D01*
X2118139Y1610101D01*
X2119668Y1610684D01*
X2121196Y1610101D01*
X2122288Y1608935D01*
X2122943Y1607185D01*
Y1599018D01*
G01X2134985Y1593185D02*
X2137168Y1596101D01*
X2138260Y1599018D01*
Y1610684D01*
X2137168Y1613601D01*
X2134985Y1616518D01*
G01X1986890Y1633668D02*
Y1651168D01*
X1991256D01*
X1993003Y1650293D01*
X1994313Y1649126D01*
X1995405Y1647377D01*
X1996278Y1645334D01*
X1996496Y1642418D01*
X1996278Y1639501D01*
X1995405Y1637459D01*
X1994313Y1635709D01*
X1993003Y1634543D01*
X1991256Y1633668D01*
X1986890D01*
G01X2004826D02*
Y1651168D01*
X2010066D01*
X2011813Y1650293D01*
X2013123Y1648251D01*
X2013560Y1645918D01*
X2013123Y1643585D01*
X2012031Y1641835D01*
X2010066Y1640959D01*
X2004826D01*
G01X2041573Y1651168D02*
X2046813D01*
G01X2044193D02*
Y1633668D01*
G01X2041573D02*
X2046813D01*
G01X2056016D02*
Y1651168D01*
X2061693Y1636585D01*
X2067370Y1651168D01*
Y1633668D01*
G01X2074826D02*
Y1651168D01*
X2080066D01*
X2081813Y1650293D01*
X2083123Y1648251D01*
X2083560Y1645918D01*
X2083123Y1643585D01*
X2082031Y1641835D01*
X2080066Y1640959D01*
X2074826D01*
G01X2101060Y1633668D02*
X2092326D01*
Y1651168D01*
X2101060D01*
G01X2097566Y1642710D02*
X2092326D01*
G01X2109390Y1633668D02*
Y1651168D01*
X2113756D01*
X2115503Y1650293D01*
X2116813Y1649126D01*
X2117905Y1647377D01*
X2118778Y1645334D01*
X2118996Y1642418D01*
X2118778Y1639501D01*
X2117905Y1637459D01*
X2116813Y1635709D01*
X2115503Y1634543D01*
X2113756Y1633668D01*
X2109390D01*
G01X2126234D02*
X2131693Y1651168D01*
X2137152Y1633668D01*
G01X2135186Y1639793D02*
X2128199D01*
G01X2144171Y1633668D02*
Y1651168D01*
X2154215Y1633668D01*
Y1651168D01*
G01X2171496Y1649709D02*
X2170186Y1650585D01*
X2168658Y1651168D01*
X2166911D01*
X2164946Y1650293D01*
X2163418Y1648835D01*
X2162326Y1647084D01*
X2161453Y1644168D01*
X2161234Y1641543D01*
X2161671Y1638918D01*
X2162326Y1637168D01*
X2163636Y1635418D01*
X2165165Y1634251D01*
X2166693Y1633668D01*
X2168221D01*
X2169750Y1634251D01*
X2171060Y1635126D01*
X2172152Y1636292D01*
G01X2188560Y1633668D02*
X2179826D01*
Y1651168D01*
X2188560D01*
G01X2185066Y1642710D02*
X2179826D01*
G01X2219193Y1651168D02*
Y1633668D01*
G01X2214171Y1651168D02*
X2224215D01*
G01X2231234Y1633668D02*
X2236693Y1651168D01*
X2242152Y1633668D01*
G01X2240186Y1639793D02*
X2233199D01*
G01X2255939Y1643001D02*
X2256813Y1643876D01*
X2257468Y1645334D01*
X2257905Y1647377D01*
X2257468Y1649126D01*
X2256595Y1650293D01*
X2255066Y1651168D01*
X2249171D01*
Y1633668D01*
X2256376D01*
X2257905Y1634834D01*
X2258778Y1636585D01*
X2259215Y1638626D01*
X2258778Y1640668D01*
X2257468Y1642418D01*
X2255939Y1643001D01*
X2249171D01*
G01X2267326Y1651168D02*
Y1633668D01*
X2276060D01*
G01X2293560D02*
X2284826D01*
Y1651168D01*
X2293560D01*
G01X2290066Y1642710D02*
X2284826D01*
G01X2306693Y1633085D02*
X2306256Y1633376D01*
Y1633960D01*
X2306693Y1634251D01*
X2307130Y1633960D01*
Y1633376D01*
X2306693Y1633085D01*
G01Y1640959D02*
X2306256Y1641251D01*
Y1641835D01*
X2306693Y1642126D01*
X2307130Y1641835D01*
Y1641251D01*
X2306693Y1640959D01*
G01X2337326Y1651168D02*
Y1633668D01*
X2346060D01*
G01X2359193D02*
Y1651168D01*
X2356573Y1647668D01*
G01Y1633668D02*
X2361813D01*
G01X2372545Y1648251D02*
X2373855Y1650001D01*
X2375383Y1650876D01*
X2377130Y1651168D01*
X2379313Y1650585D01*
X2380841Y1649126D01*
X2381278Y1647377D01*
X2381060Y1645626D01*
X2380186Y1644168D01*
X2375820Y1641251D01*
X2373855Y1639210D01*
X2372545Y1636292D01*
X2372108Y1633668D01*
X2381278D01*
G01X2046393Y1564368D02*
X2047921Y1564660D01*
X2049668Y1565534D01*
X2050760Y1566992D01*
X2051196Y1569035D01*
X2050760Y1571076D01*
X2049450Y1572826D01*
X2047485Y1573701D01*
X2045301D01*
X2043991Y1574285D01*
X2042899Y1575743D01*
X2042463Y1577784D01*
X2043118Y1579826D01*
X2044646Y1581285D01*
X2046393Y1581868D01*
X2048139Y1581285D01*
X2049668Y1579826D01*
X2050323Y1577784D01*
X2049886Y1575743D01*
X2048795Y1574285D01*
X2047485Y1573701D01*
X2045301D01*
X2043336Y1572826D01*
X2042026Y1571076D01*
X2041590Y1569035D01*
X2042026Y1566992D01*
X2043118Y1565534D01*
X2044865Y1564660D01*
X2046393Y1564368D01*
G01X2059090Y1566992D02*
X2060399Y1565534D01*
X2061928Y1564660D01*
X2063893Y1564368D01*
X2065858Y1564951D01*
X2067386Y1566118D01*
X2068478Y1568159D01*
X2068696Y1570493D01*
X2068260Y1572826D01*
X2067168Y1574285D01*
X2065639Y1575451D01*
X2064111Y1575743D01*
X2062583Y1575451D01*
X2060618Y1574285D01*
X2061273Y1581868D01*
X2067168D01*
G01X2081393Y1563785D02*
X2080956Y1564076D01*
Y1564660D01*
X2081393Y1564951D01*
X2081830Y1564660D01*
Y1564076D01*
X2081393Y1563785D01*
G01X2098893Y1581868D02*
X2097146Y1581285D01*
X2095836Y1579826D01*
X2094963Y1578077D01*
X2094308Y1575743D01*
X2094090Y1573118D01*
X2094308Y1570493D01*
X2094963Y1568159D01*
X2095836Y1566409D01*
X2097146Y1564951D01*
X2098893Y1564368D01*
X2100639Y1564951D01*
X2101950Y1566409D01*
X2102823Y1568159D01*
X2103478Y1570493D01*
X2103696Y1573118D01*
X2103478Y1575743D01*
X2102823Y1578077D01*
X2101950Y1579826D01*
X2100639Y1581285D01*
X2098893Y1581868D01*
G01X2037643Y1529718D02*
Y1547218D01*
X2035023Y1543718D01*
G01Y1529718D02*
X2040263D01*
G01X2055143Y1547218D02*
X2053396Y1546635D01*
X2052086Y1545176D01*
X2051213Y1543427D01*
X2050558Y1541093D01*
X2050340Y1538468D01*
X2050558Y1535843D01*
X2051213Y1533509D01*
X2052086Y1531759D01*
X2053396Y1530301D01*
X2055143Y1529718D01*
X2056889Y1530301D01*
X2058200Y1531759D01*
X2059073Y1533509D01*
X2059728Y1535843D01*
X2059946Y1538468D01*
X2059728Y1541093D01*
X2059073Y1543427D01*
X2058200Y1545176D01*
X2056889Y1546635D01*
X2055143Y1547218D01*
G01X2072643D02*
X2070896Y1546635D01*
X2069586Y1545176D01*
X2068713Y1543427D01*
X2068058Y1541093D01*
X2067840Y1538468D01*
X2068058Y1535843D01*
X2068713Y1533509D01*
X2069586Y1531759D01*
X2070896Y1530301D01*
X2072643Y1529718D01*
X2074389Y1530301D01*
X2075700Y1531759D01*
X2076573Y1533509D01*
X2077228Y1535843D01*
X2077446Y1538468D01*
X2077228Y1541093D01*
X2076573Y1543427D01*
X2075700Y1545176D01*
X2074389Y1546635D01*
X2072643Y1547218D01*
G01X2090143Y1529135D02*
X2089706Y1529426D01*
Y1530010D01*
X2090143Y1530301D01*
X2090580Y1530010D01*
Y1529426D01*
X2090143Y1529135D01*
G01X2107643Y1547218D02*
X2105896Y1546635D01*
X2104586Y1545176D01*
X2103713Y1543427D01*
X2103058Y1541093D01*
X2102840Y1538468D01*
X2103058Y1535843D01*
X2103713Y1533509D01*
X2104586Y1531759D01*
X2105896Y1530301D01*
X2107643Y1529718D01*
X2109389Y1530301D01*
X2110700Y1531759D01*
X2111573Y1533509D01*
X2112228Y1535843D01*
X2112446Y1538468D01*
X2112228Y1541093D01*
X2111573Y1543427D01*
X2110700Y1545176D01*
X2109389Y1546635D01*
X2107643Y1547218D01*
G01X2197343Y1616518D02*
X2200399Y1599018D01*
X2203893Y1616518D01*
X2207386Y1599018D01*
X2210443Y1616518D01*
G01X2218773D02*
X2224013D01*
G01X2221393D02*
Y1599018D01*
G01X2218773D02*
X2224013D01*
G01X2234090D02*
Y1616518D01*
X2238456D01*
X2240203Y1615643D01*
X2241513Y1614476D01*
X2242605Y1612727D01*
X2243478Y1610684D01*
X2243696Y1607768D01*
X2243478Y1604851D01*
X2242605Y1602809D01*
X2241513Y1601059D01*
X2240203Y1599893D01*
X2238456Y1599018D01*
X2234090D01*
G01X2256393Y1616518D02*
Y1599018D01*
G01X2251371Y1616518D02*
X2261415D01*
G01X2269308Y1599018D02*
Y1616518D01*
G01X2278478D02*
Y1599018D01*
G01Y1607768D02*
X2269308D01*
G01X2290301Y1593185D02*
X2288118Y1596101D01*
X2287026Y1599018D01*
Y1610684D01*
X2288118Y1613601D01*
X2290301Y1616518D01*
G01X2302343Y1599018D02*
Y1610684D01*
G01Y1607476D02*
X2302998Y1608935D01*
X2304090Y1610101D01*
X2305618Y1610684D01*
X2307146Y1610101D01*
X2308238Y1608935D01*
X2308893Y1607476D01*
Y1599018D01*
G01Y1607476D02*
X2309548Y1608935D01*
X2310639Y1610101D01*
X2312168Y1610684D01*
X2313696Y1610101D01*
X2314788Y1608935D01*
X2315443Y1607185D01*
Y1599018D01*
G01X2326393Y1610684D02*
Y1599018D01*
G01Y1615351D02*
X2325956Y1615643D01*
Y1616226D01*
X2326393Y1616518D01*
X2326830Y1616226D01*
Y1615643D01*
X2326393Y1615351D01*
G01X2343893Y1599018D02*
Y1616518D01*
G01X2358118Y1601059D02*
X2359210Y1599893D01*
X2360738Y1599018D01*
X2362048D01*
X2363358Y1599601D01*
X2364231Y1600476D01*
X2364668Y1601642D01*
X2364450Y1603393D01*
X2363576Y1604268D01*
X2359646Y1606018D01*
X2358773Y1608060D01*
X2359210Y1609518D01*
X2360083Y1610393D01*
X2361393Y1610684D01*
X2362703Y1610393D01*
X2364013Y1609518D01*
G01X2379985Y1593185D02*
X2382168Y1596101D01*
X2383260Y1599018D01*
Y1610684D01*
X2382168Y1613601D01*
X2379985Y1616518D01*
G01X2234745Y1571659D02*
X2236273Y1573701D01*
X2237583Y1574868D01*
X2239330Y1575451D01*
X2240858Y1574868D01*
X2241950Y1573701D01*
X2242823Y1571951D01*
X2243041Y1569910D01*
X2242823Y1568159D01*
X2241950Y1566409D01*
X2240639Y1564951D01*
X2239111Y1564368D01*
X2237365Y1564951D01*
X2235836Y1566701D01*
X2234963Y1569326D01*
X2234745Y1572243D01*
X2235181Y1576034D01*
X2235836Y1578077D01*
X2236928Y1580118D01*
X2238456Y1581576D01*
X2239985Y1581868D01*
X2241513Y1581285D01*
X2242605Y1579826D01*
G01X2256393Y1563785D02*
X2255956Y1564076D01*
Y1564660D01*
X2256393Y1564951D01*
X2256830Y1564660D01*
Y1564076D01*
X2256393Y1563785D01*
G01X2269090Y1566992D02*
X2270399Y1565534D01*
X2271928Y1564660D01*
X2273893Y1564368D01*
X2275858Y1564951D01*
X2277386Y1566118D01*
X2278478Y1568159D01*
X2278696Y1570493D01*
X2278260Y1572826D01*
X2277168Y1574285D01*
X2275639Y1575451D01*
X2274111Y1575743D01*
X2272583Y1575451D01*
X2270618Y1574285D01*
X2271273Y1581868D01*
X2277168D01*
G01X2287463Y1563785D02*
X2295323Y1581868D01*
G01X2304090Y1566992D02*
X2305399Y1565534D01*
X2306928Y1564660D01*
X2308893Y1564368D01*
X2310858Y1564951D01*
X2312386Y1566118D01*
X2313478Y1568159D01*
X2313696Y1570493D01*
X2313260Y1572826D01*
X2312168Y1574285D01*
X2310639Y1575451D01*
X2309111Y1575743D01*
X2307583Y1575451D01*
X2305618Y1574285D01*
X2306273Y1581868D01*
X2312168D01*
G01X2326393Y1563785D02*
X2325956Y1564076D01*
Y1564660D01*
X2326393Y1564951D01*
X2326830Y1564660D01*
Y1564076D01*
X2326393Y1563785D01*
G01X2343893Y1581868D02*
X2342146Y1581285D01*
X2340836Y1579826D01*
X2339963Y1578077D01*
X2339308Y1575743D01*
X2339090Y1573118D01*
X2339308Y1570493D01*
X2339963Y1568159D01*
X2340836Y1566409D01*
X2342146Y1564951D01*
X2343893Y1564368D01*
X2345639Y1564951D01*
X2346950Y1566409D01*
X2347823Y1568159D01*
X2348478Y1570493D01*
X2348696Y1573118D01*
X2348478Y1575743D01*
X2347823Y1578077D01*
X2346950Y1579826D01*
X2345639Y1581285D01*
X2343893Y1581868D01*
G01X2234090Y1532342D02*
X2235399Y1530884D01*
X2236928Y1530010D01*
X2238893Y1529718D01*
X2240858Y1530301D01*
X2242386Y1531468D01*
X2243478Y1533509D01*
X2243696Y1535843D01*
X2243260Y1538176D01*
X2242168Y1539635D01*
X2240639Y1540801D01*
X2239111Y1541093D01*
X2237583Y1540801D01*
X2235618Y1539635D01*
X2236273Y1547218D01*
X2242168D01*
G01X2256393Y1529135D02*
X2255956Y1529426D01*
Y1530010D01*
X2256393Y1530301D01*
X2256830Y1530010D01*
Y1529426D01*
X2256393Y1529135D01*
G01X2273893Y1547218D02*
X2272146Y1546635D01*
X2270836Y1545176D01*
X2269963Y1543427D01*
X2269308Y1541093D01*
X2269090Y1538468D01*
X2269308Y1535843D01*
X2269963Y1533509D01*
X2270836Y1531759D01*
X2272146Y1530301D01*
X2273893Y1529718D01*
X2275639Y1530301D01*
X2276950Y1531759D01*
X2277823Y1533509D01*
X2278478Y1535843D01*
X2278696Y1538468D01*
X2278478Y1541093D01*
X2277823Y1543427D01*
X2276950Y1545176D01*
X2275639Y1546635D01*
X2273893Y1547218D01*
G01X2287463Y1529135D02*
X2295323Y1547218D01*
G01X2304745Y1537009D02*
X2306273Y1539051D01*
X2307583Y1540218D01*
X2309330Y1540801D01*
X2310858Y1540218D01*
X2311950Y1539051D01*
X2312823Y1537301D01*
X2313041Y1535260D01*
X2312823Y1533509D01*
X2311950Y1531759D01*
X2310639Y1530301D01*
X2309111Y1529718D01*
X2307365Y1530301D01*
X2305836Y1532051D01*
X2304963Y1534676D01*
X2304745Y1537593D01*
X2305181Y1541384D01*
X2305836Y1543427D01*
X2306928Y1545468D01*
X2308456Y1546926D01*
X2309985Y1547218D01*
X2311513Y1546635D01*
X2312605Y1545176D01*
G01X2326393Y1529135D02*
X2325956Y1529426D01*
Y1530010D01*
X2326393Y1530301D01*
X2326830Y1530010D01*
Y1529426D01*
X2326393Y1529135D01*
G01X2339090Y1532342D02*
X2340399Y1530884D01*
X2341928Y1530010D01*
X2343893Y1529718D01*
X2345858Y1530301D01*
X2347386Y1531468D01*
X2348478Y1533509D01*
X2348696Y1535843D01*
X2348260Y1538176D01*
X2347168Y1539635D01*
X2345639Y1540801D01*
X2344111Y1541093D01*
X2342583Y1540801D01*
X2340618Y1539635D01*
X2341273Y1547218D01*
X2347168D01*
G01X2461590Y1564368D02*
Y1581868D01*
X2465956D01*
X2467703Y1580993D01*
X2469013Y1579826D01*
X2470105Y1578077D01*
X2470978Y1576034D01*
X2471196Y1573118D01*
X2470978Y1570201D01*
X2470105Y1568159D01*
X2469013Y1566409D01*
X2467703Y1565243D01*
X2465956Y1564368D01*
X2461590D01*
G01X2479526D02*
Y1581868D01*
X2484766D01*
X2486513Y1580993D01*
X2487823Y1578951D01*
X2488260Y1576618D01*
X2487823Y1574285D01*
X2486731Y1572535D01*
X2484766Y1571659D01*
X2479526D01*
G01X2461590Y1529718D02*
Y1547218D01*
X2465956D01*
X2467703Y1546343D01*
X2469013Y1545176D01*
X2470105Y1543427D01*
X2470978Y1541384D01*
X2471196Y1538468D01*
X2470978Y1535551D01*
X2470105Y1533509D01*
X2469013Y1531759D01*
X2467703Y1530593D01*
X2465956Y1529718D01*
X2461590D01*
G01X2479526D02*
Y1547218D01*
X2484766D01*
X2486513Y1546343D01*
X2487823Y1544301D01*
X2488260Y1541968D01*
X2487823Y1539635D01*
X2486731Y1537885D01*
X2484766Y1537009D01*
X2479526D01*
G01X2448893Y1616518D02*
Y1599018D01*
G01X2443871Y1616518D02*
X2453915D01*
G01X2466393Y1599018D02*
Y1606893D01*
X2462026Y1616518D01*
G01X2470760D02*
X2466393Y1606893D01*
G01X2479526Y1599018D02*
Y1616518D01*
X2484766D01*
X2486513Y1615643D01*
X2487823Y1613601D01*
X2488260Y1611268D01*
X2487823Y1608935D01*
X2486731Y1607185D01*
X2484766Y1606309D01*
X2479526D01*
G01X2505760Y1599018D02*
X2497026D01*
Y1616518D01*
X2505760D01*
G01X2502266Y1608060D02*
X2497026D01*
G01X2549526Y1599018D02*
Y1616518D01*
X2554985D01*
X2556731Y1615643D01*
X2557823Y1614476D01*
X2558260Y1612143D01*
X2557823Y1609809D01*
X2556513Y1608351D01*
X2554985Y1607476D01*
X2549526D01*
G01X2554985D02*
X2558260Y1599018D01*
G01X2568118Y1606893D02*
X2575105D01*
X2574450Y1608935D01*
X2573358Y1610101D01*
X2571830Y1610684D01*
X2570301Y1610393D01*
X2568991Y1609518D01*
X2568118Y1607476D01*
X2567681Y1605726D01*
Y1603976D01*
X2568118Y1602226D01*
X2569210Y1600476D01*
X2570520Y1599310D01*
X2572048Y1599018D01*
X2573576Y1599601D01*
X2575105Y1601351D01*
G01X2587583Y1599018D02*
Y1613893D01*
X2588020Y1615351D01*
X2588893Y1616226D01*
X2590203Y1616518D01*
X2591513Y1615935D01*
X2592168Y1614476D01*
G01X2589548Y1609518D02*
X2585181D01*
G01X2606393Y1598435D02*
X2605956Y1598726D01*
Y1599310D01*
X2606393Y1599601D01*
X2606830Y1599310D01*
Y1598726D01*
X2606393Y1598435D01*
G01X2637026Y1599018D02*
Y1616518D01*
X2642266D01*
X2644013Y1615643D01*
X2645323Y1613601D01*
X2645760Y1611268D01*
X2645323Y1608935D01*
X2644231Y1607185D01*
X2642266Y1606309D01*
X2637026D01*
G01X2658893Y1599018D02*
Y1616518D01*
G01X2680323Y1599018D02*
Y1610684D01*
G01Y1608643D02*
X2679450Y1609809D01*
X2678139Y1610393D01*
X2676611Y1610684D01*
X2675083Y1610101D01*
X2673773Y1608935D01*
X2672899Y1607185D01*
X2672463Y1604851D01*
X2672899Y1602518D01*
X2673773Y1600768D01*
X2675083Y1599601D01*
X2676611Y1599018D01*
X2678139Y1599310D01*
X2679450Y1600184D01*
X2680323Y1601351D01*
G01X2690181Y1599018D02*
Y1610684D01*
G01Y1607768D02*
X2691055Y1609226D01*
X2692365Y1610393D01*
X2694111Y1610684D01*
X2695639Y1610393D01*
X2696950Y1609226D01*
X2697605Y1607185D01*
Y1599018D01*
G01X2708118Y1606893D02*
X2715105D01*
X2714450Y1608935D01*
X2713358Y1610101D01*
X2711830Y1610684D01*
X2710301Y1610393D01*
X2708991Y1609518D01*
X2708118Y1607476D01*
X2707681Y1605726D01*
Y1603976D01*
X2708118Y1602226D01*
X2709210Y1600476D01*
X2710520Y1599310D01*
X2712048Y1599018D01*
X2713576Y1599601D01*
X2715105Y1601351D01*
G01X2610776Y1581868D02*
Y1564368D01*
X2619510D01*
G01X2632643D02*
Y1581868D01*
X2630023Y1578368D01*
G01Y1564368D02*
X2635263D01*
G01X2650143D02*
Y1581868D01*
X2647523Y1578368D01*
G01Y1564368D02*
X2652763D01*
G01X2610776Y1547218D02*
Y1529718D01*
X2619510D01*
G01X2632643D02*
Y1547218D01*
X2630023Y1543718D01*
G01Y1529718D02*
X2635263D01*
G01X2650143D02*
Y1547218D01*
X2647523Y1543718D01*
G01Y1529718D02*
X2652763D01*
G01X2829193Y1576034D02*
Y1564368D01*
G01Y1580701D02*
X2828756Y1580993D01*
Y1581576D01*
X2829193Y1581868D01*
X2829630Y1581576D01*
Y1580993D01*
X2829193Y1580701D01*
G01X2843418Y1566409D02*
X2844510Y1565243D01*
X2846038Y1564368D01*
X2847348D01*
X2848658Y1564951D01*
X2849531Y1565826D01*
X2849968Y1566992D01*
X2849750Y1568743D01*
X2848876Y1569618D01*
X2844946Y1571368D01*
X2844073Y1573410D01*
X2844510Y1574868D01*
X2845383Y1575743D01*
X2846693Y1576034D01*
X2848003Y1575743D01*
X2849313Y1574868D01*
G01X2876671Y1564368D02*
Y1581868D01*
X2886715Y1564368D01*
Y1581868D01*
G01X2899193Y1564368D02*
X2897446Y1564660D01*
X2895918Y1565826D01*
X2894608Y1567576D01*
X2893734Y1569618D01*
X2893298Y1571951D01*
Y1574285D01*
X2893734Y1576618D01*
X2894608Y1578660D01*
X2895918Y1580409D01*
X2897446Y1581576D01*
X2899193Y1581868D01*
X2900939Y1581576D01*
X2902468Y1580409D01*
X2903778Y1578660D01*
X2904652Y1576618D01*
X2905088Y1574285D01*
Y1571951D01*
X2904652Y1569618D01*
X2903778Y1567576D01*
X2902468Y1565826D01*
X2900939Y1564660D01*
X2899193Y1564368D01*
G01X2916693Y1581868D02*
Y1564368D01*
G01X2911671Y1581868D02*
X2921715D01*
G01X2947981Y1576034D02*
Y1567868D01*
X2948855Y1565826D01*
X2950165Y1564660D01*
X2951693Y1564368D01*
X2953221Y1564660D01*
X2954531Y1565826D01*
X2955405Y1567868D01*
G01Y1564368D02*
Y1576034D01*
G01X2965918Y1566409D02*
X2967010Y1565243D01*
X2968538Y1564368D01*
X2969848D01*
X2971158Y1564951D01*
X2972031Y1565826D01*
X2972468Y1566992D01*
X2972250Y1568743D01*
X2971376Y1569618D01*
X2967446Y1571368D01*
X2966573Y1573410D01*
X2967010Y1574868D01*
X2967883Y1575743D01*
X2969193Y1576034D01*
X2970503Y1575743D01*
X2971813Y1574868D01*
G01X2983418Y1572243D02*
X2990405D01*
X2989750Y1574285D01*
X2988658Y1575451D01*
X2987130Y1576034D01*
X2985601Y1575743D01*
X2984291Y1574868D01*
X2983418Y1572826D01*
X2982981Y1571076D01*
Y1569326D01*
X2983418Y1567576D01*
X2984510Y1565826D01*
X2985820Y1564660D01*
X2987348Y1564368D01*
X2988876Y1564951D01*
X2990405Y1566701D01*
G01X3008123Y1581868D02*
Y1564368D01*
G01Y1566992D02*
X3007250Y1565534D01*
X3005939Y1564660D01*
X3004411Y1564368D01*
X3002665Y1564951D01*
X3001355Y1566409D01*
X3000481Y1568159D01*
X3000263Y1570201D01*
X3000481Y1572243D01*
X3001355Y1573993D01*
X3002665Y1575451D01*
X3004411Y1576034D01*
X3005939Y1575743D01*
X3007031Y1575159D01*
X3008123Y1573993D01*
G01X2754390Y1598435D02*
X2763996Y1611268D01*
G01X2759193Y1613601D02*
Y1596101D01*
G01X2763996Y1598435D02*
X2754390Y1611268D01*
G01X2752643Y1604851D02*
X2765743D01*
G01X2791355D02*
X2797031D01*
G01X2824390Y1599018D02*
Y1616518D01*
X2828756D01*
X2830503Y1615643D01*
X2831813Y1614476D01*
X2832905Y1612727D01*
X2833778Y1610684D01*
X2833996Y1607768D01*
X2833778Y1604851D01*
X2832905Y1602809D01*
X2831813Y1601059D01*
X2830503Y1599893D01*
X2828756Y1599018D01*
X2824390D01*
G01X2843418Y1606893D02*
X2850405D01*
X2849750Y1608935D01*
X2848658Y1610101D01*
X2847130Y1610684D01*
X2845601Y1610393D01*
X2844291Y1609518D01*
X2843418Y1607476D01*
X2842981Y1605726D01*
Y1603976D01*
X2843418Y1602226D01*
X2844510Y1600476D01*
X2845820Y1599310D01*
X2847348Y1599018D01*
X2848876Y1599601D01*
X2850405Y1601351D01*
G01X2860481Y1599018D02*
Y1610684D01*
G01Y1607768D02*
X2861355Y1609226D01*
X2862665Y1610393D01*
X2864411Y1610684D01*
X2865939Y1610393D01*
X2867250Y1609226D01*
X2867905Y1607185D01*
Y1599018D01*
G01X2881693D02*
X2880383Y1599310D01*
X2879073Y1600476D01*
X2878199Y1602518D01*
X2877763Y1604851D01*
X2878199Y1607185D01*
X2879073Y1609226D01*
X2880383Y1610393D01*
X2881693Y1610684D01*
X2883003Y1610393D01*
X2884313Y1609226D01*
X2885186Y1607185D01*
X2885405Y1604851D01*
X2885186Y1602518D01*
X2884313Y1600476D01*
X2883003Y1599310D01*
X2881693Y1599018D01*
G01X2899193Y1616518D02*
Y1599018D01*
G01X2896136Y1610684D02*
X2902250D01*
G01X2913418Y1606893D02*
X2920405D01*
X2919750Y1608935D01*
X2918658Y1610101D01*
X2917130Y1610684D01*
X2915601Y1610393D01*
X2914291Y1609518D01*
X2913418Y1607476D01*
X2912981Y1605726D01*
Y1603976D01*
X2913418Y1602226D01*
X2914510Y1600476D01*
X2915820Y1599310D01*
X2917348Y1599018D01*
X2918876Y1599601D01*
X2920405Y1601351D01*
G01X2930918Y1601059D02*
X2932010Y1599893D01*
X2933538Y1599018D01*
X2934848D01*
X2936158Y1599601D01*
X2937031Y1600476D01*
X2937468Y1601642D01*
X2937250Y1603393D01*
X2936376Y1604268D01*
X2932446Y1606018D01*
X2931573Y1608060D01*
X2932010Y1609518D01*
X2932883Y1610393D01*
X2934193Y1610684D01*
X2935503Y1610393D01*
X2936813Y1609518D01*
G01X2969193Y1616518D02*
Y1599018D01*
G01X2966136Y1610684D02*
X2972250D01*
G01X2982981Y1599018D02*
Y1616518D01*
G01Y1608060D02*
X2984073Y1609518D01*
X2985165Y1610393D01*
X2986911Y1610684D01*
X2988221Y1610393D01*
X2989750Y1609226D01*
X2990405Y1607476D01*
Y1599018D01*
G01X3008123D02*
Y1610684D01*
G01Y1608643D02*
X3007250Y1609809D01*
X3005939Y1610393D01*
X3004411Y1610684D01*
X3002883Y1610101D01*
X3001573Y1608935D01*
X3000699Y1607185D01*
X3000263Y1604851D01*
X3000699Y1602518D01*
X3001573Y1600768D01*
X3002883Y1599601D01*
X3004411Y1599018D01*
X3005939Y1599310D01*
X3007250Y1600184D01*
X3008123Y1601351D01*
G01X3021693Y1616518D02*
Y1599018D01*
G01X3018636Y1610684D02*
X3024750D01*
G01X3056693Y1616518D02*
Y1599018D01*
G01X3053636Y1610684D02*
X3059750D01*
G01X3070481Y1599018D02*
Y1616518D01*
G01Y1608060D02*
X3071573Y1609518D01*
X3072665Y1610393D01*
X3074411Y1610684D01*
X3075721Y1610393D01*
X3077250Y1609226D01*
X3077905Y1607476D01*
Y1599018D01*
G01X3091693Y1610684D02*
Y1599018D01*
G01Y1615351D02*
X3091256Y1615643D01*
Y1616226D01*
X3091693Y1616518D01*
X3092130Y1616226D01*
Y1615643D01*
X3091693Y1615351D01*
G01X3105918Y1601059D02*
X3107010Y1599893D01*
X3108538Y1599018D01*
X3109848D01*
X3111158Y1599601D01*
X3112031Y1600476D01*
X3112468Y1601642D01*
X3112250Y1603393D01*
X3111376Y1604268D01*
X3107446Y1606018D01*
X3106573Y1608060D01*
X3107010Y1609518D01*
X3107883Y1610393D01*
X3109193Y1610684D01*
X3110503Y1610393D01*
X3111813Y1609518D01*
G01X3141573Y1616518D02*
X3146813D01*
G01X3144193D02*
Y1599018D01*
G01X3141573D02*
X3146813D01*
G01X3155143D02*
Y1610684D01*
G01Y1607476D02*
X3155798Y1608935D01*
X3156890Y1610101D01*
X3158418Y1610684D01*
X3159946Y1610101D01*
X3161038Y1608935D01*
X3161693Y1607476D01*
Y1599018D01*
G01Y1607476D02*
X3162348Y1608935D01*
X3163439Y1610101D01*
X3164968Y1610684D01*
X3166496Y1610101D01*
X3167588Y1608935D01*
X3168243Y1607185D01*
Y1599018D01*
G01X3175263Y1593185D02*
Y1610684D01*
G01Y1608060D02*
X3176355Y1609518D01*
X3177446Y1610393D01*
X3179193Y1610684D01*
X3180721Y1610393D01*
X3182250Y1608935D01*
X3182905Y1606893D01*
X3183123Y1604851D01*
X3182905Y1602809D01*
X3182250Y1600768D01*
X3180939Y1599601D01*
X3179193Y1599018D01*
X3177665Y1599310D01*
X3176136Y1600184D01*
X3175263Y1601351D01*
G01X3193418Y1606893D02*
X3200405D01*
X3199750Y1608935D01*
X3198658Y1610101D01*
X3197130Y1610684D01*
X3195601Y1610393D01*
X3194291Y1609518D01*
X3193418Y1607476D01*
X3192981Y1605726D01*
Y1603976D01*
X3193418Y1602226D01*
X3194510Y1600476D01*
X3195820Y1599310D01*
X3197348Y1599018D01*
X3198876Y1599601D01*
X3200405Y1601351D01*
G01X3218123Y1616518D02*
Y1599018D01*
G01Y1601642D02*
X3217250Y1600184D01*
X3215939Y1599310D01*
X3214411Y1599018D01*
X3212665Y1599601D01*
X3211355Y1601059D01*
X3210481Y1602809D01*
X3210263Y1604851D01*
X3210481Y1606893D01*
X3211355Y1608643D01*
X3212665Y1610101D01*
X3214411Y1610684D01*
X3215939Y1610393D01*
X3217031Y1609809D01*
X3218123Y1608643D01*
G01X3235623Y1599018D02*
Y1610684D01*
G01Y1608643D02*
X3234750Y1609809D01*
X3233439Y1610393D01*
X3231911Y1610684D01*
X3230383Y1610101D01*
X3229073Y1608935D01*
X3228199Y1607185D01*
X3227763Y1604851D01*
X3228199Y1602518D01*
X3229073Y1600768D01*
X3230383Y1599601D01*
X3231911Y1599018D01*
X3233439Y1599310D01*
X3234750Y1600184D01*
X3235623Y1601351D01*
G01X3245481Y1599018D02*
Y1610684D01*
G01Y1607768D02*
X3246355Y1609226D01*
X3247665Y1610393D01*
X3249411Y1610684D01*
X3250939Y1610393D01*
X3252250Y1609226D01*
X3252905Y1607185D01*
Y1599018D01*
G01X3270186Y1609226D02*
X3268658Y1610393D01*
X3267348Y1610684D01*
X3265601Y1610101D01*
X3264291Y1608935D01*
X3263418Y1606893D01*
X3263199Y1604851D01*
X3263418Y1602809D01*
X3264291Y1601059D01*
X3265601Y1599601D01*
X3267348Y1599018D01*
X3268876Y1599601D01*
X3270186Y1600768D01*
G01X3280918Y1606893D02*
X3287905D01*
X3287250Y1608935D01*
X3286158Y1610101D01*
X3284630Y1610684D01*
X3283101Y1610393D01*
X3281791Y1609518D01*
X3280918Y1607476D01*
X3280481Y1605726D01*
Y1603976D01*
X3280918Y1602226D01*
X3282010Y1600476D01*
X3283320Y1599310D01*
X3284848Y1599018D01*
X3286376Y1599601D01*
X3287905Y1601351D01*
G01X0Y-137756D02*
G03X15000Y-152756I15000J0D01*
G01X0Y-137756D02*
G03X15000Y-152756I15000J0D01*
G01X0Y-11811D02*
Y-137756D01*
G01Y-11811D02*
Y-137756D01*
G01X854331Y-152756D02*
X15000D01*
G01X854331D02*
X15000D01*
G01X23622Y-7874D02*
G03Y0I0J3937D01*
G01Y-7874D02*
G03Y0I0J3937D01*
G01X0Y3937D02*
G03X3937Y0I3937J0D01*
G01Y-7874D02*
X23622D01*
G01X0Y3937D02*
G03X3937Y0I3937J0D01*
G01Y-7874D02*
X23622D01*
G01X3937D02*
G03X0Y-11811I0J-3937D01*
G01X3937Y-7874D02*
G03X0Y-11811I0J-3937D01*
G01X3937Y0D02*
X397638D01*
G01X3937D02*
X397638D01*
G01X0Y1370866D02*
Y3937D01*
G01Y1370866D02*
Y3937D01*
G01X3937Y1374803D02*
G03X0Y1370866I0J-3937D01*
G01X3937Y1374803D02*
G03X0Y1370866I0J-3937D01*
G01X23622Y1374803D02*
G03Y1382677I0J3937D01*
G01Y1374803D02*
G03Y1382677I0J3937D01*
G01X3937D02*
X23622D01*
G01X0Y1386614D02*
G03X3937Y1382677I3937J0D01*
G01D02*
X23622D01*
G01X0Y1386614D02*
G03X3937Y1382677I3937J0D01*
G01Y1374803D02*
X746850D01*
G01D02*
X3937D01*
G01X0Y1386614D02*
Y1643268D01*
G01Y1386614D02*
Y1643268D01*
G01X15000Y1658268D02*
G03X0Y1643268I0J-15000D01*
G01X15000Y1658268D02*
G03X0Y1643268I0J-15000D01*
G01X775591Y1658268D02*
X15000D01*
G01X775591D02*
X15000D01*
G01X54331Y-7874D02*
X323228D01*
G01X54331D02*
X323228D01*
G01X54331Y0D02*
G03Y-7874I0J-3937D01*
G01Y0D02*
G03Y-7874I0J-3937D01*
G01Y1382677D02*
G03Y1374803I0J-3937D01*
G01Y1382677D02*
G03Y1374803I0J-3937D01*
G01Y1382677D02*
X353740D01*
G01X54331D02*
X353740D01*
G01X114295Y378885D02*
G03X148106I16905J-13531D01*
G01X114295D02*
G03X148106I16905J-13531D01*
G01X114295D02*
G03X121220Y392016I-30737J24602D01*
G01X114295Y378885D02*
G03X121220Y392016I-30737J24602D01*
G01X114295Y831641D02*
G03X121220Y844772I-30737J24601D01*
G01X114295Y831641D02*
G03X121220Y844772I-30737J24602D01*
G01X114295Y831641D02*
G03X148106I16905J-13531D01*
G01X114295D02*
G03X148106I16905J-13531D01*
G01X114295Y1284397D02*
G03X148106I16905J-13531D01*
G01X114295D02*
G03X148106I16905J-13531D01*
G01X114295D02*
G03X121220Y1297528I-30737J24601D01*
G01X114295Y1284397D02*
G03X121220Y1297528I-30737J24602D01*
G01X141181Y392016D02*
G03X121220I-9980J-3039D01*
G01X141181D02*
G03X148106Y378885I37662J11471D01*
G01X141181Y392016D02*
G03X121220I-9980J-3039D01*
G01X141181D02*
G03X148106Y378885I37662J11471D01*
G01X141181Y844772D02*
G03X148106Y831641I37662J11471D01*
G01X141181Y844772D02*
G03X148106Y831641I37662J11471D01*
G01X141181Y844772D02*
G03X121220I-9980J-3040D01*
G01X141181D02*
G03X121220I-9980J-3039D01*
G01X141181Y1297528D02*
G03X121220I-9980J-3040D01*
G01X141181D02*
G03X148106Y1284397I37662J11471D01*
G01X141181Y1297528D02*
G03X121220I-9980J-3040D01*
G01X141181D02*
G03X148106Y1284397I37662J11471D01*
G01X323228Y-7874D02*
G03Y0I0J3937D01*
G01Y-7874D02*
G03Y0I0J3937D01*
G01X362598D02*
G03Y-7874I0J-3937D01*
G01Y0D02*
G03Y-7874I0J-3937D01*
G01X362327Y378885D02*
G03X396138I16905J-13531D01*
G01X362327D02*
G03X396138I16905J-13531D01*
G01X362327D02*
G03X369252Y392016I-30737J24602D01*
G01X362327Y378885D02*
G03X369252Y392016I-30737J24602D01*
G01X362327Y831641D02*
G03X369252Y844772I-30737J24602D01*
G01X362327Y831641D02*
G03X369252Y844772I-30737J24602D01*
G01X362327Y831641D02*
G03X396138I16905J-13531D01*
G01X362327D02*
G03X396138I16905J-13531D01*
G01X362327Y1284397D02*
G03X396138I16905J-13531D01*
G01X362327D02*
G03X396138I16905J-13531D01*
G01X362327D02*
G03X369252Y1297528I-30737J24602D01*
G01X362327Y1284397D02*
G03X369252Y1297528I-30737J24602D01*
G01X353740Y1374803D02*
G03Y1382677I0J3937D01*
G01Y1374803D02*
G03Y1382677I0J3937D01*
G01X401575Y3937D02*
Y55118D01*
G01X397638Y0D02*
G03X401575Y3937I0J3937D01*
G01X409449D02*
Y51181D01*
G01X397638Y-7874D02*
G03X409449Y3937I0J11811D01*
G01X397638Y0D02*
G03X401575Y3937I0J3937D01*
G01D02*
Y55118D01*
G01X409449Y3937D02*
Y51181D01*
G01X397638Y-7874D02*
G03X409449Y3937I0J11811D01*
G01X362598Y-7874D02*
X397638D01*
G01X362598D02*
X397638D01*
G01X405512Y59055D02*
G03X401575Y55118I0J-3937D01*
G01X405512Y59055D02*
G03X401575Y55118I0J-3937D01*
G01X405512Y59055D02*
X586614D01*
G01X409449Y51181D02*
X582677D01*
G01X405512Y59055D02*
X586614D01*
G01X409449Y51181D02*
X582677D01*
G01X389213Y392016D02*
G03X396138Y378885I37662J11471D01*
G01X389213Y392016D02*
G03X396138Y378885I37662J11471D01*
G01X389213Y392016D02*
G03X369252I-9981J-3039D01*
G01X389213D02*
G03X369252I-9981J-3039D01*
G01X389213Y844772D02*
G03X396138Y831641I37662J11471D01*
G01X389213Y844772D02*
G03X396138Y831641I37662J11471D01*
G01X389213Y844772D02*
G03X369252I-9981J-3040D01*
G01X389213D02*
G03X369252I-9981J-3039D01*
G01X389213Y1297528D02*
G03X396138Y1284397I37662J11471D01*
G01X389213Y1297528D02*
G03X396138Y1284397I37662J11471D01*
G01X389213Y1297528D02*
G03X369252I-9981J-3040D01*
G01X389213D02*
G03X369252I-9981J-3040D01*
G01X393110Y1382677D02*
G03Y1374803I0J-3937D01*
G01Y1382677D02*
X692520D01*
G01X393110D02*
X692520D01*
G01X393110D02*
G03Y1374803I0J-3937D01*
G01X523327Y829921D02*
G03X483169I-20079J0D01*
G01X523327D02*
G03I-20079J0D01*
G01X483169D02*
G03X523327I20079J0D01*
G01X594488Y-7874D02*
X628765D01*
G01X594488D02*
X628765D01*
G01X590551Y55118D02*
Y3937D01*
G01D02*
G03X594488Y0I3937J0D01*
G01X582677Y51181D02*
Y3937D01*
G01D02*
G03X594488Y-7874I11811J0D01*
G01X590551Y55118D02*
Y3937D01*
G01D02*
G03X594488Y0I3937J0D01*
G01X582677Y51181D02*
Y3937D01*
G01D02*
G03X594488Y-7874I11811J0D01*
G01Y0D02*
X783465D01*
G01X594488D02*
X783465D01*
G01X590551Y55118D02*
G03X586614Y59055I-3937J0D01*
G01X590551Y55118D02*
G03X586614Y59055I-3937J0D01*
G01X628765Y-7874D02*
G03Y0I0J3937D01*
G01Y-7874D02*
G03Y0I0J3937D01*
G01X610358Y378885D02*
G03X644169I16906J-13531D01*
G01X610358D02*
G03X644169I16906J-13531D01*
G01X637244Y392016D02*
G03X644169Y378885I37662J11471D01*
G01X637244Y392016D02*
G03X644169Y378885I37662J11471D01*
G01X637244Y392016D02*
G03X617283I-9980J-3039D01*
G01X637244D02*
G03X617283I-9980J-3039D01*
G01X610358Y378885D02*
G03X617283Y392016I-30737J24602D01*
G01X610358Y378885D02*
G03X617283Y392016I-30737J24602D01*
G01X637244Y844772D02*
G03X644169Y831641I37662J11471D01*
G01X637244Y844772D02*
G03X644169Y831641I37662J11471D01*
G01X610358D02*
G03X617283Y844772I-30737J24601D01*
G01X610358Y831641D02*
G03X617283Y844772I-30737J24602D01*
G01X610358Y831641D02*
G03X644169I16906J-13531D01*
G01X610358D02*
G03X644169I16906J-13531D01*
G01X637244Y844772D02*
G03X617283I-9980J-3040D01*
G01X637244D02*
G03X617283I-9980J-3039D01*
G01X610358Y1284397D02*
G03X644169I16906J-13531D01*
G01X610358D02*
G03X644169I16906J-13531D01*
G01X637244Y1297528D02*
G03X644169Y1284397I37662J11471D01*
G01X637244Y1297528D02*
G03X644169Y1284397I37662J11471D01*
G01X610358D02*
G03X617283Y1297528I-30737J24601D01*
G01X637244D02*
G03X617283I-9980J-3040D01*
G01X610358Y1284397D02*
G03X617283Y1297528I-30737J24602D01*
G01X637244D02*
G03X617283I-9980J-3040D01*
G01X659474Y0D02*
G03Y-7874I0J-3937D01*
G01Y0D02*
G03Y-7874I0J-3937D01*
G01D02*
X780203D01*
G01X659474D02*
X780203D01*
G01X692520Y1374803D02*
G03Y1382677I0J3937D01*
G01Y1374803D02*
G03Y1382677I0J3937D01*
G01X746850Y1374803D02*
G03X750787Y1378740I0J3937D01*
G01X746850Y1374803D02*
G03X750787Y1378740I0J3937D01*
G01X723228Y1382677D02*
G03Y1374803I0J-3937D01*
G01Y1382677D02*
X742913D01*
G01X723228D02*
X742913D01*
G01X723228D02*
G03Y1374803I0J-3937D01*
G01X742913Y1464567D02*
Y1382677D01*
G01Y1464567D02*
Y1382677D01*
G01X754724Y1476378D02*
G03X742913Y1464567I0J-11811D01*
G01X754724Y1476378D02*
G03X742913Y1464567I0J-11811D01*
G01X862205Y-7874D02*
X791339D01*
G01X787402Y-3937D02*
G03X791339Y-7874I3937J0D01*
G01X787402Y-3937D02*
G03X791339Y-7874I3937J0D01*
G01D02*
X862205D01*
G01X858268Y-15748D02*
X791339D01*
G01X858268D02*
X791339D01*
G01X787402Y-3937D02*
G03X783465Y0I-3937J0D01*
G01X787402Y-3937D02*
G03X783465Y0I-3937J0D01*
G01X780203Y-7874D02*
G03X791339Y-15748I11136J3937D01*
G01X780203Y-7874D02*
G03X791339Y-15748I11136J3937D01*
G01X779551Y264712D02*
G03X813362I16905J-13531D01*
G01X779551D02*
G03X813362I16905J-13531D01*
G01X779551D02*
G03X786476Y277843I-30737J24601D01*
G01X806437D02*
G03X786476I-9981J-3040D01*
G01X779551Y264712D02*
G03X786476Y277843I-30737J24602D01*
G01X806437D02*
G03X786476I-9981J-3040D01*
G01X779551Y737153D02*
G03X786476Y750284I-30737J24601D01*
G01X779551Y737154D02*
G03X786476Y750284I-30736J24602D01*
G01X779551Y737153D02*
G03X813362I16905J-13531D01*
G01X779551D02*
G03X813362I16905J-13531D01*
G01X806437Y750284D02*
G03X786476I-9981J-3040D01*
G01X806437D02*
G03X786476I-9981J-3040D01*
G01X750787Y1464567D02*
Y1378740D01*
G01Y1464567D02*
Y1378740D01*
G01X783465Y1468504D02*
G03X787402Y1472441I0J3937D01*
G01X783465Y1468504D02*
G03X787402Y1472441I0J3937D01*
G01X783465Y1468504D02*
X754724D01*
G01D02*
G03X750787Y1464567I0J-3937D01*
G01X783465Y1468504D02*
X754724D01*
G01D02*
G03X750787Y1464567I0J-3937D01*
G01X779528Y1476378D02*
X754724D01*
G01X779528D02*
X754724D01*
G01X787402Y1654331D02*
Y1472441D01*
G01X779528Y1596063D02*
Y1476378D01*
G01X787402Y1654331D02*
Y1472441D01*
G01X779528Y1596063D02*
Y1476378D01*
G01X787402Y1596063D02*
G03X779528I-3937J0D01*
G01X787402D02*
G03X779528I-3937J0D01*
G01X1216535Y1658268D02*
X791339D01*
G01D02*
G03X787402Y1654331I0J-3937D01*
G01X779528D02*
G03X775591Y1658268I-3937J0D01*
G01X1216535D02*
X791339D01*
G01D02*
G03X787402Y1654331I0J-3937D01*
G01X779528D02*
G03X775591Y1658268I-3937J0D01*
G01X779528Y1654331D02*
Y1626772D01*
G01D02*
G03X787402I3937J0D01*
G01X779528Y1654331D02*
Y1626772D01*
G01D02*
G03X787402I3937J0D01*
G01X806437Y277843D02*
G03X813362Y264712I37662J11471D01*
G01X806437Y277843D02*
G03X813362Y264712I37662J11471D01*
G01X806437Y750284D02*
G03X813362Y737153I37662J11471D01*
G01X806437Y750284D02*
G03X813362Y737154I37661J11472D01*
G01X866142Y-148819D02*
Y-11811D01*
G01Y-148819D02*
G03X870079Y-152756I3937J0D01*
G01X866142Y-11811D02*
Y-148819D01*
G01D02*
G03X870079Y-152756I3937J0D01*
G01X866142Y-129134D02*
G03X858268I-3937J0D01*
G01X866142D02*
G03X858268I-3937J0D01*
G01Y-148819D02*
Y-129134D01*
G01X854331Y-152756D02*
G03X858268Y-148819I0J3937D01*
G01D02*
Y-129134D01*
G01X854331Y-152756D02*
G03X858268Y-148819I0J3937D01*
G01X1177165Y-152756D02*
X870079D01*
G01D02*
X1177165D01*
G01X858268Y-98425D02*
Y-15748D01*
G01Y-98425D02*
Y-15748D01*
G01Y-98425D02*
G03X866142I3937J0D01*
G01X858268D02*
G03X866142I3937J0D01*
G01Y-11811D02*
G03X862205Y-7874I-3937J0D01*
G01X866142Y-11811D02*
G03X862205Y-7874I-3937J0D01*
G01X927032Y-57820D02*
G03X962731I17850J-12259D01*
G01X927032Y-57821D02*
G03X962732I17850J-12258D01*
G01X927032Y-57820D02*
G03X935199Y-42571I-64908J44575D01*
G01X954565D02*
G03X935199I-9683J-3885D01*
G01X927032Y-57821D02*
G03X935199Y-42571I-64909J44573D01*
G01X954564D02*
G03X935199I-9682J-3885D01*
G01X944512Y1089122D02*
G03X978323I16905J-13531D01*
G01X944512Y1089121D02*
G03X978323I16905J-13531D01*
G01X944512Y1431641D02*
G03X978323I16905J-13531D01*
G01X944512D02*
G03X978323I16905J-13531D01*
G01X954565Y-42571D02*
G03X962731Y-57820I73077J29322D01*
G01X954564Y-42570D02*
G03X962732Y-57821I73076J29324D01*
G01X971398Y1102252D02*
G03X978323Y1089122I37661J11472D01*
G01X971398Y1102252D02*
G03X978323Y1089121I37662J11471D01*
G01X971398Y1102252D02*
G03X951437I-9980J-3039D01*
G01X971398D02*
G03X951437I-9980J-3039D01*
G01X944512Y1089122D02*
G03X951437Y1102252I-30737J24602D01*
G01X944512Y1089121D02*
G03X951437Y1102252I-30737J24602D01*
G01X971398Y1444772D02*
G03X978323Y1431641I37662J11471D01*
G01X971398Y1444772D02*
G03X978323Y1431641I37662J11471D01*
G01X971398Y1444772D02*
G03X951437I-9980J-3040D01*
G01X944512Y1431641D02*
G03X951437Y1444772I-30737J24602D01*
G01X944512Y1431641D02*
G03X951437Y1444772I-30737J24602D01*
G01X971398D02*
G03X951437I-9980J-3039D01*
G01X1181102Y-148819D02*
Y-3937D01*
G01X1177165Y-152756D02*
G03X1181102Y-148819I0J3937D01*
G01X1177165Y-152756D02*
G03X1181102Y-148819I0J3937D01*
G01D02*
Y-3937D01*
G01Y-94488D02*
G03X1188976I3937J0D01*
G01X1181102D02*
G03X1188976I3937J0D01*
G01Y-125197D02*
G03X1181102I-3937J0D01*
G01X1188976D02*
G03X1181102I-3937J0D01*
G01X1185039Y0D02*
G03X1181102Y-3937I0J-3937D01*
G01X1185039Y0D02*
G03X1181102Y-3937I0J-3937D01*
G01X1164984Y557626D02*
G03X1198795I16906J-13531D01*
G01X1164984Y557625D02*
G03X1198795I16906J-13531D01*
G01X1191870Y570756D02*
G03X1171909I-9980J-3039D01*
G01X1191870D02*
G03X1171909I-9980J-3039D01*
G01X1164984Y557626D02*
G03X1171909Y570756I-30736J24602D01*
G01X1164984Y557625D02*
G03X1171909Y570756I-30737J24602D01*
G01X1164984Y971011D02*
G03X1198795I16906J-13531D01*
G01X1164984D02*
G03X1198795I16906J-13531D01*
G01X1191870Y984142D02*
G03X1171909I-9980J-3040D01*
G01X1191870D02*
G03X1171909I-9980J-3039D01*
G01X1164984Y971011D02*
G03X1171909Y984142I-30737J24602D01*
G01X1164984Y971011D02*
G03X1171909Y984142I-30737J24602D01*
G01X1164173Y1378740D02*
Y1468504D01*
G01X1930906Y1374803D02*
X1168110D01*
G01X1164173Y1378740D02*
G03X1168110Y1374803I3937J0D01*
G01X1172047Y1382677D02*
Y1464567D01*
G01X1195669Y1382677D02*
X1172047D01*
G01X1930906Y1374803D02*
X1168110D01*
G01X1164173Y1378740D02*
G03X1168110Y1374804I3937J1D01*
G01X1164173Y1378740D02*
Y1468504D01*
G01X1172047Y1382677D02*
Y1464567D01*
G01X1195669Y1382677D02*
X1172047D01*
G01X1168110Y1472441D02*
G03X1164173Y1468504I0J-3937D01*
G01X1168110Y1472441D02*
G03X1164173Y1468504I0J-3937D01*
G01X1172047Y1464567D02*
X1216535D01*
G01X1172047D02*
X1216535D01*
G01X1168110Y1472441D02*
X1216535D01*
G01X1168110D02*
X1216535D01*
G01X1164984Y1561563D02*
G03X1171909Y1574693I-30736J24602D01*
G01X1164984Y1561562D02*
G03X1171909Y1574693I-30737J24602D01*
G01X1164984Y1561563D02*
G03X1198795I16906J-13531D01*
G01X1164984Y1561562D02*
G03X1198795I16906J-13531D01*
G01X1191870Y1574693D02*
G03X1171909I-9980J-3039D01*
G01X1191870D02*
G03X1171909I-9980J-3039D01*
G01X1188976Y-148819D02*
Y-125197D01*
G01Y-148819D02*
G03X1192913Y-152756I3937J0D01*
G01X1188976Y-148819D02*
Y-125197D01*
G01Y-148819D02*
G03X1192913Y-152756I3937J0D01*
G01D02*
X1919843D01*
G01X1192913D02*
X1919843D01*
G01X1188976Y-94488D02*
Y-7874D01*
G01Y-94488D02*
Y-7874D01*
G01X1185039Y0D02*
X1366142D01*
G01X1188976Y-7874D02*
X1315748D01*
G01X1185039Y0D02*
X1366142D01*
G01X1188976Y-7874D02*
X1315748D01*
G01X1191870Y570756D02*
G03X1198795Y557626I37662J11472D01*
G01X1191870Y570756D02*
G03X1198795Y557626I37662J11472D01*
G01X1191870Y984142D02*
G03X1198795Y971011I37662J11471D01*
G01X1191870Y984142D02*
G03X1198795Y971011I37662J11471D01*
G01X1524606Y1382677D02*
X1226378D01*
G01X1524606D02*
X1226378D01*
G01X1195669Y1374803D02*
G03Y1382677I0J3937D01*
G01X1226378D02*
G03Y1374803I0J-3937D01*
G01X1195669D02*
G03Y1382677I0J3937D01*
G01X1226378D02*
G03Y1374803I0J-3937D01*
G01X1216535Y1464567D02*
G03X1228346Y1476378I0J11811D01*
G01X1216535Y1464567D02*
G03X1228346Y1476378I0J11811D01*
G01Y1592126D02*
Y1476378D01*
G01Y1592126D02*
Y1476378D01*
G01X1220472Y1654331D02*
Y1476378D01*
G01X1216535Y1472441D02*
G03X1220472Y1476378I0J3937D01*
G01X1216535Y1472441D02*
G03X1220472Y1476378I0J3937D01*
G01D02*
Y1654331D01*
G01X1191870Y1574693D02*
G03X1198795Y1561563I37662J11472D01*
G01X1191870Y1574693D02*
G03X1198795Y1561562I37662J11471D01*
G01X1228346Y1592126D02*
G03X1220472I-3937J0D01*
G01X1228346D02*
G03X1220472I-3937J0D01*
G01X1232283Y1658268D02*
X1442382D01*
G01X1232283D02*
G03X1228346Y1654331I0J-3937D01*
G01X1232283Y1658268D02*
X1442382D01*
G01X1232283D02*
G03X1228346Y1654331I0J-3937D01*
G01D02*
Y1622835D01*
G01Y1654331D02*
Y1622835D01*
G01X1220472Y1654331D02*
G03X1216535Y1658268I-3937J0D01*
G01X1220472Y1654331D02*
G03X1216535Y1658268I-3937J0D01*
G01X1220472Y1622835D02*
G03X1228346I3937J0D01*
G01X1220472D02*
G03X1228346I3937J0D01*
G01X1284965Y378885D02*
G03X1318776I16906J-13531D01*
G01X1284965D02*
G03X1318775I16905J-13531D01*
G01X1284965Y831641D02*
G03X1318776I16906J-13531D01*
G01X1284965D02*
G03X1318775I16905J-13531D01*
G01X1284965Y1284397D02*
G03X1318776I16906J-13531D01*
G01X1284965D02*
G03X1318775I16905J-13531D01*
G01X1315748Y-7874D02*
G03Y0I0J3937D01*
G01Y-7874D02*
G03Y0I0J3937D01*
G01X1311850Y392016D02*
G03X1291890I-9980J-3040D01*
G01X1311850D02*
G03X1318776Y378885I37662J11473D01*
G01X1311851Y392016D02*
G03X1291890I-9980J-3039D01*
G01X1311851D02*
G03X1318775Y378885I37663J11469D01*
G01X1284965D02*
G03X1291890Y392016I-30737J24602D01*
G01X1284965Y378885D02*
G03X1291890Y392016I-30737J24602D01*
G01X1284965Y831641D02*
G03X1291890Y844772I-30737J24602D01*
G01X1311850D02*
G03X1318776Y831641I37662J11473D01*
G01X1284965D02*
G03X1291890Y844772I-30737J24602D01*
G01X1311851D02*
G03X1318775Y831641I37663J11469D01*
G01X1311850Y844772D02*
G03X1291890I-9980J-3040D01*
G01X1311851D02*
G03X1291890I-9980J-3039D01*
G01X1284965Y1284397D02*
G03X1291890Y1297528I-30737J24602D01*
G01X1311850D02*
G03X1291890I-9980J-3040D01*
G01X1311850D02*
G03X1318776Y1284397I37661J11473D01*
G01X1284965D02*
G03X1291890Y1297528I-30737J24602D01*
G01X1311851D02*
G03X1291890I-9980J-3040D01*
G01X1311851D02*
G03X1318775Y1284397I37663J11469D01*
G01X1377953Y3937D02*
Y51181D01*
G01Y3937D02*
Y51181D01*
G01X1370079Y3937D02*
Y55118D01*
G01X1366142Y0D02*
G03X1370079Y3937I0J3937D01*
G01X1366142Y-7874D02*
G03X1377953Y3937I0J11811D01*
G01X1346457Y-7874D02*
X1366142D01*
G01Y0D02*
G03X1370079Y3937I0J3937D01*
G01D02*
Y55118D01*
G01X1346457Y-7874D02*
X1366142D01*
G01D02*
G03X1377953Y3937I0J11811D01*
G01X1346457Y0D02*
G03Y-7874I0J-3937D01*
G01Y0D02*
G03Y-7874I0J-3937D01*
G01X1374016Y59055D02*
G03X1370079Y55118I0J-3937D01*
G01X1374016Y59056D02*
G03X1370079Y55118I0J-3937D01*
G01X1374016Y59055D02*
X1555118D01*
G01X1377953Y51181D02*
X1551181D01*
G01X1374016Y59055D02*
X1555118D01*
G01X1377953Y51181D02*
X1551181D01*
G01X1442382Y1658268D02*
G03X1450256I3937J0D01*
G01X1442382D02*
G03X1450256I3937J0D01*
G01D02*
X1919843D01*
G01X1450256D02*
X1919843D01*
G01X1562992Y0D02*
X1930906D01*
G01X1559055Y55118D02*
Y3937D01*
G01D02*
G03X1562992Y0I3937J0D01*
G01Y-7874D02*
X1593701D01*
G01X1559055Y55118D02*
Y3937D01*
G01D02*
G03X1562992Y0I3937J0D01*
G01D02*
X1930906D01*
G01X1562992Y-7874D02*
X1593701D01*
G01X1551181Y51181D02*
Y3937D01*
G01D02*
G03X1562992Y-7874I11811J0D01*
G01X1551181Y51181D02*
Y3937D01*
G01D02*
G03X1562992Y-7874I11811J0D01*
G01X1559055Y55118D02*
G03X1555118Y59055I-3937J0D01*
G01X1559055Y55118D02*
G03X1555118Y59055I-3937J0D01*
G01X1532996Y378885D02*
G03X1566807I16906J-13531D01*
G01X1532996D02*
G03X1566807I16906J-13531D01*
G01X1559882Y392016D02*
G03X1566807Y378885I37662J11471D01*
G01X1559882Y392016D02*
G03X1566807Y378885I37662J11471D01*
G01X1559882Y392016D02*
G03X1539921I-9980J-3039D01*
G01X1559882D02*
G03X1539921I-9980J-3039D01*
G01X1532996Y378885D02*
G03X1539921Y392016I-30737J24602D01*
G01X1532996Y378885D02*
G03X1539921Y392016I-30737J24602D01*
G01X1559882Y844772D02*
G03X1566807Y831641I37662J11471D01*
G01X1559882Y844772D02*
G03X1566807Y831641I37662J11471D01*
G01X1532996D02*
G03X1539921Y844772I-30737J24602D01*
G01X1532996Y831641D02*
G03X1539921Y844772I-30737J24602D01*
G01X1532996Y831641D02*
G03X1566807I16906J-13531D01*
G01X1532996D02*
G03X1566807I16906J-13531D01*
G01X1559882Y844772D02*
G03X1539921I-9980J-3040D01*
G01X1559882D02*
G03X1539921I-9980J-3039D01*
G01X1532996Y1284397D02*
G03X1566807I16906J-13531D01*
G01X1532996D02*
G03X1566807I16906J-13531D01*
G01X1559882Y1297528D02*
G03X1566807Y1284397I37662J11471D01*
G01X1559882Y1297528D02*
G03X1566807Y1284397I37662J11471D01*
G01X1559882Y1297528D02*
G03X1539921I-9980J-3040D01*
G01X1532996Y1284397D02*
G03X1539921Y1297528I-30737J24602D01*
G01X1532996Y1284397D02*
G03X1539921Y1297528I-30737J24602D01*
G01X1559882D02*
G03X1539921I-9980J-3040D01*
G01X1563976Y1382677D02*
G03Y1374803I0J-3937D01*
G01Y1382677D02*
G03Y1374803I0J-3937D01*
G01X1524606D02*
G03Y1382677I0J3937D01*
G01Y1374803D02*
G03Y1382677I0J3937D01*
G01X1864567D02*
X1563976D01*
G01X1864567D02*
X1563976D01*
G01X1593701Y-7874D02*
G03Y0I0J3937D01*
G01Y-7874D02*
G03Y0I0J3937D01*
G01X1633071D02*
G03Y-7874I0J-3937D01*
G01D02*
X1880512D01*
G01X1633071D02*
X1880512D01*
G01X1633071Y0D02*
G03Y-7874I0J-3937D01*
G01X1693996Y829921D02*
G03X1653839I-20078J0D01*
G01X1693996D02*
G03I-20079J0D01*
G01X1653839D02*
G03X1693996I20078J0D01*
G01X1781028Y378885D02*
G03X1814839I16906J-13531D01*
G01X1781028D02*
G03X1814838I16905J-13531D01*
G01X1807913Y392016D02*
G03X1814839Y378885I37662J11473D01*
G01X1807914Y392016D02*
G03X1814838Y378885I37663J11469D01*
G01X1807913Y392016D02*
G03X1787953I-9980J-3040D01*
G01X1807914D02*
G03X1787953I-9980J-3039D01*
G01X1781028Y378885D02*
G03X1787953Y392016I-30737J24602D01*
G01X1781028Y378885D02*
G03X1787953Y392016I-30737J24602D01*
G01X1807913Y844772D02*
G03X1814839Y831641I37662J11473D01*
G01X1807914Y844772D02*
G03X1814838Y831641I37663J11469D01*
G01X1781028D02*
G03X1787953Y844772I-30737J24602D01*
G01X1781028Y831641D02*
G03X1787953Y844772I-30737J24602D01*
G01X1781028Y831641D02*
G03X1814839I16906J-13531D01*
G01X1781028D02*
G03X1814838I16905J-13531D01*
G01X1807913Y844772D02*
G03X1787953I-9980J-3040D01*
G01X1807914D02*
G03X1787953I-9980J-3039D01*
G01X1781028Y1284397D02*
G03X1814839I16906J-13531D01*
G01X1781028D02*
G03X1814838I16905J-13531D01*
G01X1807913Y1297528D02*
G03X1814839Y1284397I37661J11473D01*
G01X1807914Y1297528D02*
G03X1814838Y1284397I37663J11469D01*
G01X1807913Y1297528D02*
G03X1787953I-9980J-3040D01*
G01X1781028Y1284397D02*
G03X1787953Y1297528I-30737J24602D01*
G01X1781028Y1284397D02*
G03X1787953Y1297528I-30737J24602D01*
G01X1807914D02*
G03X1787953I-9980J-3040D01*
G01X1911220Y0D02*
G03Y-7874I0J-3937D01*
G01Y0D02*
G03Y-7874I0J-3937D01*
G01X1880512D02*
G03Y0I0J3937D01*
G01Y-7874D02*
G03Y0I0J3937D01*
G01X1930906Y1382677D02*
X1895276D01*
G01D02*
G03Y1374803I0J-3937D01*
G01X1930906Y1382677D02*
X1895276D01*
G01D02*
G03Y1374803I0J-3937D01*
G01X1864567D02*
G03Y1382677I0J3937D01*
G01Y1374803D02*
G03Y1382677I0J3937D01*
G01X1919843Y-152756D02*
G03X1934843Y-137756I0J15000D01*
G01X1919843Y-152756D02*
G03X1934843Y-137756I0J15000D01*
G01Y-11811D02*
Y-137756D01*
G01Y-11811D02*
Y-137756D01*
G01X1930906Y0D02*
G03X1934843Y3937I0J3937D01*
G01X1930906Y0D02*
G03X1934843Y3937I0J3937D01*
G01Y-11811D02*
G03X1930906Y-7874I-3937J0D01*
G01X1934843Y-11811D02*
G03X1930906Y-7874I-3937J0D01*
G01X1911220D02*
X1930906D01*
G01X1911220D02*
X1930906D01*
G01X1934843Y1370866D02*
Y3937D01*
G01D02*
Y1370866D01*
G01D02*
G03X1930906Y1374803I-3937J0D01*
G01X1934843Y1370866D02*
G03X1930906Y1374803I-3937J0D01*
G01Y1382677D02*
G03X1934843Y1386614I0J3937D01*
G01X1930906Y1382677D02*
G03X1934843Y1386614I0J3937D01*
G01D02*
Y1643268D01*
G01Y1386614D02*
Y1643268D01*
G01D02*
G03X1919843Y1658268I-15000J0D01*
G01X1934843Y1643268D02*
G03X1919843Y1658268I-15000J0D01*
G54D13*
G01X424450Y87902D02*
Y118755D01*
G01X425600Y87902D02*
Y118635D01*
G01X427690Y84662D02*
G02X424450Y87902I0J3240D01*
G01X427690Y85812D02*
G02X425600Y87902I0J2090D01*
G01X429069Y84662D02*
X427690D01*
G01X429069Y85812D02*
X427690D01*
G01X425600Y87902D02*
Y118635D01*
G01X424450Y87902D02*
Y118755D01*
G01X427690Y85812D02*
G02X425600Y87902I0J2090D01*
G01X427690Y84662D02*
G02X424450Y87902I0J3240D01*
G01X429069Y85812D02*
X427690D01*
G01X429069Y84662D02*
X427690D01*
G01X432693Y90683D02*
Y124467D01*
G01X433843Y90683D02*
Y124347D01*
G01X434777Y88599D02*
G02X432693Y90683I0J2084D01*
G01X434777Y89749D02*
G02X433843Y90683I0J934D01*
G01X436156Y88599D02*
X434777D01*
G01X436156Y89749D02*
X434777D01*
G01X433843Y90683D02*
Y124347D01*
G01X432693Y90683D02*
Y124467D01*
G01X434777Y89749D02*
G02X433843Y90683I0J934D01*
G01X434777Y88599D02*
G02X432693Y90683I0J2084D01*
G01X436156Y89749D02*
X434777D01*
G01X436156Y88599D02*
X434777D01*
G01X439780Y86746D02*
Y121734D01*
G01X440930Y86746D02*
Y121614D01*
G01X441864Y84662D02*
G02X439780Y86746I0J2084D01*
G01X441864Y85812D02*
G02X440930Y86746I0J934D01*
G01X443243Y84662D02*
X441864D01*
G01X443243Y85812D02*
X441864D01*
G01X440930Y86746D02*
Y121614D01*
G01X439780Y86746D02*
Y121734D01*
G01X441864Y85812D02*
G02X440930Y86746I0J934D01*
G01X441864Y84662D02*
G02X439780Y86746I0J2084D01*
G01X443243Y85812D02*
X441864D01*
G01X443243Y84662D02*
X441864D01*
G01X446866Y90683D02*
Y122237D01*
G01X448016Y90683D02*
Y122117D01*
G01X448950Y88599D02*
G02X446866Y90683I0J2084D01*
G01X448950Y89749D02*
G02X448016Y90683I0J934D01*
G01X450329Y88599D02*
X448950D01*
G01X450329Y89749D02*
X448950D01*
G01X448016Y90683D02*
Y122117D01*
G01X446866Y90683D02*
Y122237D01*
G01X448950Y89749D02*
G02X448016Y90683I0J934D01*
G01X448950Y88599D02*
G02X446866Y90683I0J2084D01*
G01X450329Y89749D02*
X448950D01*
G01X450329Y88599D02*
X448950D01*
G01X453953Y86746D02*
Y121734D01*
G01X455103Y86746D02*
Y121614D01*
G01X456037Y84662D02*
G02X453953Y86746I0J2084D01*
G01X456037Y85812D02*
G02X455103Y86746I0J934D01*
G01X457416Y84662D02*
X456037D01*
G01X457416Y85812D02*
X456037D01*
G01X455103Y86746D02*
Y121614D01*
G01X453953Y86746D02*
Y121734D01*
G01X456037Y85812D02*
G02X455103Y86746I0J934D01*
G01X456037Y84662D02*
G02X453953Y86746I0J2084D01*
G01X457416Y85812D02*
X456037D01*
G01X457416Y84662D02*
X456037D01*
G01X429468Y142680D02*
X485577Y227446D01*
G01X430549Y142229D02*
X486407Y226616D01*
G01X424450Y118755D02*
X429468Y142681D01*
G01X425600Y118635D02*
X430549Y142229D01*
G01D02*
X486407Y226616D01*
G01X429468Y142680D02*
X485577Y227446D01*
G01X425600Y118635D02*
X430549Y142229D01*
G01X424450Y118755D02*
X429468Y142681D01*
G01X436318Y141745D02*
X486114Y216979D01*
G01X437399Y141293D02*
X486944Y216149D01*
G01X432693Y124467D02*
X436318Y141745D01*
G01X433843Y124347D02*
X437399Y141293D01*
G01D02*
X486944Y216149D01*
G01X436318Y141745D02*
X486114Y216979D01*
G01X433843Y124347D02*
X437399Y141293D01*
G01X432693Y124467D02*
X436318Y141745D01*
G01X443330Y138640D02*
X490612Y210321D01*
G01X444411Y138189D02*
X491572Y209687D01*
G01X439780Y121734D02*
X443330Y138640D01*
G01X440930Y121614D02*
X444411Y138189D01*
G01D02*
X491572Y209687D01*
G01X443330Y138640D02*
X490612Y210321D01*
G01X440930Y121614D02*
X444411Y138189D01*
G01X439780Y121734D02*
X443330Y138640D01*
G01X449909Y136734D02*
X497290Y208687D01*
G01X450990Y136284D02*
X498122Y207857D01*
G01X446866Y122237D02*
X449909Y136734D01*
G01X448016Y122117D02*
X450990Y136284D01*
G01D02*
X498122Y207857D01*
G01X449909Y136734D02*
X497290Y208687D01*
G01X448016Y122117D02*
X450990Y136284D01*
G01X446866Y122237D02*
X449909Y136734D01*
G01X456957Y136033D02*
X475261Y163832D01*
G01X458038Y135583D02*
X461924Y141484D01*
G01X453953Y121734D02*
X456957Y136033D01*
G01X455103Y121614D02*
X458038Y135583D01*
G01X456957Y136033D02*
X475261Y163832D01*
G01X458038Y135583D02*
X461924Y141484D01*
G01X456957Y136033D02*
X475261Y163832D01*
G01X455103Y121614D02*
X458038Y135583D01*
G01X453953Y121734D02*
X456957Y136033D01*
G01X461039Y90683D02*
Y122225D01*
G01X462189Y90683D02*
Y122105D01*
G01X463123Y88599D02*
G02X461039Y90683I0J2084D01*
G01X463123Y89749D02*
G02X462189Y90683I0J934D01*
G01X464502Y88599D02*
X463123D01*
G01X464502Y89749D02*
X463123D01*
G01X462189Y90683D02*
Y122105D01*
G01X461039Y90683D02*
Y122225D01*
G01X463123Y89749D02*
G02X462189Y90683I0J934D01*
G01X463123Y88599D02*
G02X461039Y90683I0J2084D01*
G01X464502Y89749D02*
X463123D01*
G01X464502Y88599D02*
X463123D01*
G01X468126Y86746D02*
Y126163D01*
G01X469276Y86746D02*
Y125818D01*
G01X470210Y84662D02*
G02X468126Y86746I0J2084D01*
G01X470210Y85812D02*
G02X469276Y86746I0J934D01*
G01X471589Y84662D02*
X470210D01*
G01X471589Y85812D02*
X470210D01*
G01X469276Y86746D02*
Y125818D01*
G01X468126Y86746D02*
Y126163D01*
G01X470210Y85812D02*
G02X469276Y86746I0J934D01*
G01X470210Y84662D02*
G02X468126Y86746I0J2084D01*
G01X471589Y85812D02*
X470210D01*
G01X471589Y84662D02*
X470210D01*
G01X475213Y90683D02*
Y125686D01*
G01X476363Y90683D02*
Y125243D01*
G01X477297Y88599D02*
G02X475213Y90683I0J2084D01*
G01X477297Y89749D02*
G02X476363Y90683I0J934D01*
G01X478676Y88599D02*
X477297D01*
G01X478676Y89749D02*
X477297D01*
G01X476363Y90683D02*
Y125243D01*
G01X475213Y90683D02*
Y125686D01*
G01X477297Y89749D02*
G02X476363Y90683I0J934D01*
G01X477297Y88599D02*
G02X475213Y90683I0J2084D01*
G01X478676Y89749D02*
X477297D01*
G01X478676Y88599D02*
X477297D01*
G01X479066Y158267D02*
X549680Y205417D01*
G01X479899Y157439D02*
X550126Y204332D01*
G01X471388Y146615D02*
X479066Y158267D01*
G01X464797Y134523D02*
X479899Y157439D01*
G01X463716Y134973D02*
X471388Y146615D01*
G01X464797Y134523D02*
X479899Y157439D01*
G01X461039Y122225D02*
X463716Y134973D01*
G01X462189Y122105D02*
X464797Y134523D01*
G01X479899Y157439D02*
X550126Y204332D01*
G01X479066Y158267D02*
X549680Y205417D01*
G01X464797Y134523D02*
X479899Y157439D01*
G01X471388Y146615D02*
X479066Y158267D01*
G01X463716Y134973D02*
X471388Y146615D01*
G01X462189Y122105D02*
X464797Y134523D01*
G01X461039Y122225D02*
X463716Y134973D01*
G01X478712Y142239D02*
X531882Y178103D01*
G01X505941Y159218D02*
X532336Y177021D01*
G01X505942Y159218D02*
X505941D01*
G01X479546Y141414D02*
X505942Y159218D01*
G01X468126Y126163D02*
X478712Y142239D01*
G01X474411Y133616D02*
X479546Y141414D01*
G01X469276Y125818D02*
X474411Y133615D01*
G01X505941Y159218D02*
X532336Y177021D01*
G01X478712Y142239D02*
X531882Y178103D01*
G01X505942Y159218D02*
X505941D01*
G01X478712Y142239D02*
X531882Y178103D01*
G01X479546Y141414D02*
X505942Y159218D01*
G01X478712Y142239D02*
X531882Y178103D01*
G01X474411Y133616D02*
X479546Y141414D01*
G01X468126Y126163D02*
X478712Y142239D01*
G01X469276Y125818D02*
X474411Y133615D01*
G01X468126Y126163D02*
X478712Y142239D01*
G01X482319Y136370D02*
X535052Y171929D01*
G01X483153Y135545D02*
X535501Y170844D01*
G01X475402Y125875D02*
X482319Y136370D01*
G01X476363Y125243D02*
X483153Y135545D01*
G01D02*
X535501Y170844D01*
G01X482319Y136370D02*
X535052Y171929D01*
G01X476363Y125243D02*
X483153Y135545D01*
G01X475402Y125875D02*
X482319Y136370D01*
G01X475261Y163832D02*
X480556Y167335D01*
G01X476093Y163002D02*
X481407Y166519D01*
G01X461924Y141484D02*
X476093Y163002D01*
G01D02*
X481407Y166519D01*
G01X475261Y163832D02*
X480556Y167335D01*
G01X461924Y141484D02*
X476093Y163002D01*
G01X493328Y212349D02*
X595589Y280523D01*
G01X490612Y210321D02*
X492496Y213177D01*
G01X491572Y209687D02*
X493328Y212349D01*
G01D02*
X595589Y280523D01*
G01X491572Y209687D02*
X493328Y212349D01*
G01X490612Y210321D02*
X492496Y213177D01*
G01X497290Y208687D02*
X583837Y265973D01*
G01X498122Y207857D02*
X584283Y264889D01*
G01X498122Y207857D02*
X584283Y264889D01*
G01X497290Y208687D02*
X583837Y265973D01*
G01X498638Y197292D02*
X556526Y214004D01*
G01X499390Y196312D02*
X556801Y212886D01*
G01X489414Y182010D02*
X498638Y197292D01*
G01X481407Y166519D02*
X499390Y196312D01*
G01X480556Y167335D02*
X489414Y182010D01*
G01X481407Y166519D02*
X499390Y196312D01*
G01D02*
X556801Y212886D01*
G01X498638Y197292D02*
X556526Y214004D01*
G01X481407Y166519D02*
X499390Y196312D01*
G01X489414Y182010D02*
X498638Y197292D01*
G01X480556Y167335D02*
X489414Y182010D01*
G01X485577Y227446D02*
X583113Y291911D01*
G01X486407Y226616D02*
X532463Y257055D01*
G01X485577Y227446D02*
X583113Y291911D01*
G01X485577Y227446D02*
X583113Y291911D01*
G01X485577Y227446D02*
X583113Y291911D01*
G01X485577Y227446D02*
X583113Y291911D01*
G01X485577Y227446D02*
X583113Y291911D01*
G01X486407Y226616D02*
X532463Y257055D01*
G01X485577Y227446D02*
X583113Y291911D01*
G01X486114Y216979D02*
X592665Y287505D01*
G01X486944Y216149D02*
X593111Y286421D01*
G01X486944Y216149D02*
X593111Y286421D01*
G01X486114Y216979D02*
X592665Y287505D01*
G01X492496Y213177D02*
X595141Y281607D01*
G01X492496Y213177D02*
X595141Y281607D01*
G01X518882Y86746D02*
Y129888D01*
G01X517732Y86746D02*
Y130233D01*
G01X516798Y84662D02*
G03X518882Y86746I0J2084D01*
G01X516798Y85812D02*
G03X517732Y86746I0J934D01*
G01X515419Y84662D02*
X516798D01*
G01X515419Y85812D02*
X516798D01*
G01X517732Y86746D02*
Y130233D01*
G01X518882Y86746D02*
Y129888D01*
G01X516798Y85812D02*
G03X517732Y86746I0J934D01*
G01X516798Y84662D02*
G03X518882Y86746I0J2084D01*
G01X515419Y85812D02*
X516798D01*
G01X515419Y84662D02*
X516798D01*
G01X525968Y90683D02*
Y129013D01*
G01X524818Y90683D02*
Y129358D01*
G01X523884Y88599D02*
G03X525968Y90683I0J2084D01*
G01X523884Y89749D02*
G03X524818Y90683I0J934D01*
G01X522505Y88599D02*
X523884D01*
G01X522505Y89749D02*
X523884D01*
G01X524818Y90683D02*
Y129358D01*
G01X525968Y90683D02*
Y129013D01*
G01X523884Y89749D02*
G03X524818Y90683I0J934D01*
G01X523884Y88599D02*
G03X525968Y90683I0J2084D01*
G01X522505Y89749D02*
X523884D01*
G01X522505Y88599D02*
X523884D01*
G01X533055Y86746D02*
Y127835D01*
G01X531905Y86746D02*
Y128180D01*
G01X530971Y84662D02*
G03X533055Y86746I0J2084D01*
G01X530971Y85812D02*
G03X531905Y86746I0J934D01*
G01X529592Y84662D02*
X530971D01*
G01X529592Y85812D02*
X530971D01*
G01X531905Y86746D02*
Y128180D01*
G01X533055Y86746D02*
Y127835D01*
G01X530971Y85812D02*
G03X531905Y86746I0J934D01*
G01X530971Y84662D02*
G03X533055Y86746I0J2084D01*
G01X529592Y85812D02*
X530971D01*
G01X529592Y84662D02*
X530971D01*
G01X540142Y90683D02*
Y124879D01*
G01X538992Y90683D02*
Y125224D01*
G01X538058Y88599D02*
G03X540142Y90683I0J2084D01*
G01X538058Y89749D02*
G03X538992Y90683I0J934D01*
G01X536679Y88599D02*
X538058D01*
G01X536679Y89749D02*
X538058D01*
G01X538992Y90683D02*
Y125224D01*
G01X540142Y90683D02*
Y124879D01*
G01X538058Y89749D02*
G03X538992Y90683I0J934D01*
G01X538058Y88599D02*
G03X540142Y90683I0J2084D01*
G01X536679Y89749D02*
X538058D01*
G01X536679Y88599D02*
X538058D01*
G01X547229Y90577D02*
Y124062D01*
G01X546079Y91727D02*
Y124303D01*
G01X547228Y86746D02*
Y90577D01*
G01X546078Y86746D02*
Y91727D01*
G01X545144Y84662D02*
G03X547228Y86746I0J2084D01*
G01X545144Y85812D02*
G03X546078Y86746I0J934D01*
G01X543765Y84662D02*
X545144D01*
G01X543765Y85812D02*
X545144D01*
G01X546079Y91727D02*
Y124303D01*
G01X547229Y90577D02*
Y124062D01*
G01X546078Y86746D02*
Y91727D01*
G01X547228Y86746D02*
Y90577D01*
G01X545144Y85812D02*
G03X546078Y86746I0J934D01*
G01X545144Y84662D02*
G03X547228Y86746I0J2084D01*
G01X543765Y85812D02*
X545144D01*
G01X543765Y84662D02*
X545144D01*
G01X554315Y90683D02*
Y123134D01*
G01X553165Y90683D02*
Y123479D01*
G01X552231Y88599D02*
G03X554315Y90683I0J2084D01*
G01X552231Y89749D02*
G03X553165Y90683I0J934D01*
G01X550852Y88599D02*
X552231D01*
G01X550852Y89749D02*
X552231D01*
G01X553165Y90683D02*
Y123479D01*
G01X554315Y90683D02*
Y123134D01*
G01X552231Y89749D02*
G03X553165Y90683I0J934D01*
G01X552231Y88599D02*
G03X554315Y90683I0J2084D01*
G01X550852Y89749D02*
X552231D01*
G01X550852Y88599D02*
X552231D01*
G01X534867Y154168D02*
X556039Y168453D01*
G01X534033Y154993D02*
X555589Y169538D01*
G01X518882Y129888D02*
X534867Y154168D01*
G01X517732Y130233D02*
X534033Y154993D01*
G01D02*
X555589Y169538D01*
G01X534867Y154168D02*
X556039Y168453D01*
G01X517732Y130233D02*
X534033Y154993D01*
G01X518882Y129888D02*
X534867Y154168D01*
G01X539706Y149874D02*
X558035Y162240D01*
G01X538872Y150700D02*
X557585Y163325D01*
G01X525968Y129013D02*
X539706Y149874D01*
G01X524818Y129358D02*
X538872Y150700D01*
G01D02*
X557585Y163325D01*
G01X539706Y149874D02*
X558035Y162240D01*
G01X524818Y129358D02*
X538872Y150700D01*
G01X525968Y129013D02*
X539706Y149874D01*
G01X543181Y143211D02*
X560453Y156337D01*
G01X542328Y144008D02*
X559970Y157415D01*
G01X538118Y135523D02*
X543181Y143211D01*
G01X531905Y128180D02*
X542328Y144008D01*
G01X533055Y127835D02*
X538118Y135522D01*
G01X531905Y128180D02*
X542328Y144008D01*
G01D02*
X559970Y157415D01*
G01X543181Y143211D02*
X560453Y156337D01*
G01X531905Y128180D02*
X542328Y144008D01*
G01X538118Y135523D02*
X543181Y143211D01*
G01X533055Y127835D02*
X538118Y135522D01*
G01X550887Y141201D02*
X564964Y150696D01*
G01X550053Y142026D02*
X564514Y151781D01*
G01X540142Y124879D02*
X550887Y141201D01*
G01X539180Y125511D02*
X550053Y142026D01*
G01X538992Y125224D02*
X539180Y125511D01*
G01X550053Y142026D02*
X564514Y151781D01*
G01X550887Y141201D02*
X564964Y150696D01*
G01X539180Y125511D02*
X550053Y142026D01*
G01X540142Y124879D02*
X550887Y141201D01*
G01X538992Y125224D02*
X539180Y125511D01*
G01X540142Y124879D02*
X550887Y141201D01*
G01X554967Y135918D02*
X559181Y138761D01*
G01X554025Y136670D02*
X558537Y139715D01*
G01X547336Y124420D02*
X554787Y135736D01*
G01X546244Y124853D02*
X554025Y136670D01*
G01D02*
X558537Y139715D01*
G01X554967Y135918D02*
X559181Y138761D01*
G01X546244Y124853D02*
X554025Y136670D01*
G01X547336Y124420D02*
X554787Y135736D01*
G01X554315Y123134D02*
X560008Y131778D01*
G01X553165Y123479D02*
X559174Y132603D01*
G01X553165Y123479D02*
X559174Y132603D01*
G01X554315Y123134D02*
X560008Y131778D01*
G01X556039Y168453D02*
X613591Y179640D01*
G01X555589Y169538D02*
X613600Y180814D01*
G01X555589Y169538D02*
X613600Y180814D01*
G01X556039Y168453D02*
X613591Y179640D01*
G01X549680Y205417D02*
X691562Y233002D01*
G01X550126Y204332D02*
X691554Y231828D01*
G01X550126Y204332D02*
X691554Y231828D01*
G01X549680Y205417D02*
X691562Y233002D01*
G01X532336Y177021D02*
X577178Y186145D01*
G01X531882Y178103D02*
X574497Y186774D01*
G01X532336Y177021D02*
X577178Y186145D01*
G01X532336Y177021D02*
X577178Y186145D01*
G01X531882Y178103D02*
X574497Y186774D01*
G01X535052Y171929D02*
X581434Y180944D01*
G01X535501Y170844D02*
X581884Y179859D01*
G01X535501Y170844D02*
X581884Y179859D01*
G01X535052Y171929D02*
X581434Y180944D01*
G01X534840Y258627D02*
X536467Y259702D01*
G01X534840Y258627D02*
X536467Y259702D01*
G01X550858Y269214D02*
X583561Y290828D01*
G01X546854Y266567D02*
X548481Y267642D01*
G01X542850Y263920D02*
X544476Y264996D01*
G01X538845Y261274D02*
X540472Y262349D01*
G01X550858Y269214D02*
X583561Y290828D01*
G01X546854Y266567D02*
X548481Y267642D01*
G01X542850Y263920D02*
X544476Y264996D01*
G01X538845Y261274D02*
X540472Y262349D01*
G01X561401Y87299D02*
Y124396D01*
G01X560251Y87299D02*
Y124741D01*
G01X558764Y84662D02*
G03X561401Y87299I0J2637D01*
G01X558764Y85812D02*
G03X560251Y87299I0J1487D01*
G01X557938Y84662D02*
X558764D01*
G01X557938Y85812D02*
X558764D01*
G01X560251Y87299D02*
Y124741D01*
G01X561401Y87299D02*
Y124396D01*
G01X558764Y85812D02*
G03X560251Y87299I0J1487D01*
G01X558764Y84662D02*
G03X561401Y87299I0J2637D01*
G01X557938Y85812D02*
X558764D01*
G01X557938Y84662D02*
X558764D01*
G01X568445Y88599D02*
X610743Y80123D01*
G01X568560Y89749D02*
X610744Y81296D01*
G01X565025Y88599D02*
X568445D01*
G01X565025Y89749D02*
X568560D01*
G01D02*
X610744Y81296D01*
G01X568445Y88599D02*
X610743Y80123D01*
G01X565025Y89749D02*
X568560D01*
G01X565025Y88599D02*
X568445D01*
G01X599070Y134308D02*
X835360Y88374D01*
G01X599070Y135480D02*
X835359Y89546D01*
G01X564852Y127656D02*
X599070Y134308D01*
G01X564403Y128741D02*
X599070Y135480D01*
G01X562505Y126073D02*
X564852Y127656D01*
G01X561671Y126898D02*
X564403Y128741D01*
G01X561401Y124396D02*
X562505Y126073D01*
G01X560251Y124741D02*
X561671Y126898D01*
G01X599070Y135480D02*
X835359Y89546D01*
G01X599070Y134308D02*
X835360Y88374D01*
G01X564403Y128741D02*
X599070Y135480D01*
G01X564852Y127656D02*
X599070Y134308D01*
G01X561671Y126898D02*
X564403Y128741D01*
G01X562505Y126073D02*
X564852Y127656D01*
G01X560251Y124741D02*
X561671Y126898D01*
G01X561401Y124396D02*
X562505Y126073D01*
G01X558035Y162240D02*
X610871Y172511D01*
G01X557585Y163325D02*
X610879Y173685D01*
G01X557585Y163325D02*
X610879Y173685D01*
G01X558035Y162240D02*
X610871Y172511D01*
G01X560453Y156337D02*
X607415Y165465D01*
G01X559970Y157415D02*
X607419Y166638D01*
G01X559970Y157415D02*
X607419Y166638D01*
G01X560453Y156337D02*
X607415Y165465D01*
G01X564964Y150696D02*
X607805Y159025D01*
G01X564515Y151781D02*
X607813Y160199D01*
G01X564515Y151781D02*
X607813Y160199D01*
G01X564964Y150696D02*
X607805Y159025D01*
G01X595871Y147970D02*
X824416Y103545D01*
G01X595871Y149142D02*
X824416Y104717D01*
G01X563501Y141677D02*
X595871Y147970D01*
G01X563051Y142762D02*
X595871Y149142D01*
G01X561341Y140220D02*
X563501Y141677D01*
G01X558537Y139715D02*
X563051Y142762D01*
G01X559181Y138761D02*
X561341Y140220D01*
G01X558537Y139715D02*
X563051Y142762D01*
G01X595871Y149142D02*
X824416Y104717D01*
G01X595871Y147970D02*
X824416Y103545D01*
G01X563051Y142762D02*
X595871Y149142D01*
G01X563501Y141677D02*
X595871Y147970D01*
G01X558537Y139715D02*
X563051Y142762D01*
G01X561341Y140220D02*
X563501Y141677D01*
G01X559181Y138761D02*
X561341Y140220D01*
G01X598628Y140755D02*
X826157Y96529D01*
G01X598628Y141927D02*
X826157Y97701D01*
G01X563072Y133843D02*
X598628Y140755D01*
G01X562623Y134928D02*
X598628Y141927D01*
G01X560008Y131778D02*
X563072Y133843D01*
G01X559174Y132603D02*
X562623Y134928D01*
G01X598628Y141927D02*
X826157Y97701D01*
G01X598628Y140755D02*
X826157Y96529D01*
G01X562623Y134928D02*
X598628Y141927D01*
G01X563072Y133843D02*
X598628Y140755D01*
G01X559174Y132603D02*
X562623Y134928D01*
G01X560008Y131778D02*
X563072Y133843D01*
G01X592975Y197983D02*
X694610Y218561D01*
G01X593423Y196900D02*
X620214Y202324D01*
G01X576729Y187228D02*
X592975Y197983D01*
G01X577178Y186145D02*
X593423Y196900D01*
G01X574497Y186774D02*
X576729Y187228D01*
G01X592975Y197983D02*
X694610Y218561D01*
G01X592975Y197983D02*
X694610Y218561D01*
G01X592975Y197983D02*
X694610Y218561D01*
G01X593423Y196900D02*
X620214Y202324D01*
G01X592975Y197983D02*
X694610Y218561D01*
G01X577178Y186145D02*
X593423Y196900D01*
G01X576729Y187228D02*
X592975Y197983D01*
G01X574497Y186774D02*
X576729Y187228D01*
G01X597457Y191753D02*
X695096Y211615D01*
G01X597911Y190671D02*
X695096Y210441D01*
G01X581434Y180944D02*
X597457Y191753D01*
G01X581884Y179859D02*
X597911Y190671D01*
G01D02*
X695096Y210441D01*
G01X597457Y191753D02*
X695096Y211615D01*
G01X581884Y179859D02*
X597911Y190671D01*
G01X581434Y180944D02*
X597457Y191753D01*
G01X556526Y214004D02*
X686667Y240478D01*
G01X556801Y212886D02*
X686664Y239303D01*
G01X556801Y212886D02*
X686664Y239303D01*
G01X556526Y214004D02*
X686667Y240478D01*
G01X583113Y291911D02*
X811061Y338289D01*
G01X583561Y290828D02*
X801562Y335182D01*
G01X583113Y291911D02*
X811061Y338289D01*
G01X583113Y291911D02*
X811061Y338289D01*
G01X583561Y290828D02*
X801562Y335182D01*
G01X583113Y291911D02*
X811061Y338289D01*
G01X592665Y287505D02*
X802367Y329156D01*
G01X593111Y286421D02*
X802404Y327990D01*
G01X593111Y286421D02*
X802404Y327990D01*
G01X592665Y287505D02*
X802367Y329156D01*
G01X595141Y281607D02*
X789212Y320153D01*
G01X595589Y280523D02*
X745956Y310388D01*
G01X595141Y281607D02*
X789212Y320153D01*
G01X595141Y281607D02*
X789212Y320153D01*
G01X595141Y281607D02*
X789212Y320153D01*
G01X595141Y281607D02*
X789212Y320153D01*
G01X595141Y281607D02*
X789212Y320153D01*
G01X595141Y281607D02*
X789212Y320153D01*
G01X595589Y280523D02*
X745956Y310388D01*
G01X595141Y281607D02*
X789212Y320153D01*
G01X583837Y265973D02*
X648044Y278725D01*
G01X584283Y264889D02*
X648268Y277597D01*
G01X584283Y264889D02*
X648268Y277597D01*
G01X583837Y265973D02*
X648044Y278725D01*
G01X610743Y80123D02*
X726556Y103139D01*
G01X610744Y81296D02*
X726562Y104313D01*
G01X610744Y81296D02*
X726562Y104313D01*
G01X610743Y80123D02*
X726556Y103139D01*
G01X610871Y172511D02*
X752232Y142904D01*
G01X610871Y172511D02*
X752232Y142904D01*
G01X607415Y165465D02*
X773605Y132030D01*
G01X607419Y166638D02*
X773609Y133203D01*
G01X607419Y166638D02*
X773609Y133203D01*
G01X607415Y165465D02*
X773605Y132030D01*
G01X607805Y159025D02*
X794256Y120290D01*
G01X607813Y160199D02*
X794264Y121464D01*
G01X607813Y160199D02*
X794264Y121464D01*
G01X607805Y159025D02*
X794256Y120290D01*
G01X613591Y179640D02*
X719993Y157355D01*
G01X613600Y180814D02*
X719999Y158529D01*
G01X613600Y180814D02*
X719999Y158529D01*
G01X613591Y179640D02*
X719993Y157355D01*
G01X610879Y173685D02*
X752238Y144078D01*
G01X610879Y173685D02*
X752238Y144078D01*
G01X632652Y204843D02*
X694606Y217386D01*
G01X627869Y203874D02*
X629780Y204261D01*
G01X623086Y202906D02*
X624997Y203293D01*
G01X632652Y204843D02*
X694606Y217386D01*
G01X627869Y203874D02*
X629780Y204261D01*
G01X623086Y202906D02*
X624997Y203293D01*
G01X648044Y278725D02*
X800003Y308905D01*
G01X648268Y277597D02*
X785866Y304924D01*
G01X648044Y278725D02*
X800003Y308905D01*
G01X648044Y278725D02*
X800003Y308905D01*
G01X648044Y278725D02*
X800003Y308905D01*
G01X648268Y277597D02*
X785866Y304924D01*
G01X648044Y278725D02*
X800003Y308905D01*
G01X695096Y211615D02*
X795365Y191218D01*
G01X695096Y210441D02*
X778358Y193503D01*
G01X695096Y211615D02*
X795365Y191218D01*
G01X695096Y211615D02*
X795365Y191218D01*
G01X695096Y210441D02*
X778358Y193503D01*
G01X695096Y211615D02*
X795365Y191218D01*
G01X691562Y233002D02*
X796117Y211104D01*
G01X691554Y231828D02*
X777006Y213931D01*
G01X691562Y233002D02*
X796117Y211104D01*
G01X691562Y233002D02*
X796117Y211104D01*
G01X691562Y233002D02*
X796117Y211104D01*
G01X691554Y231828D02*
X777006Y213931D01*
G01X691562Y233002D02*
X796117Y211104D01*
G01X694610Y218561D02*
X780179Y200681D01*
G01X694606Y217386D02*
X780173Y199507D01*
G01X694606Y217386D02*
X780173Y199507D01*
G01X694610Y218561D02*
X780179Y200681D01*
G01X686667Y240478D02*
X793238Y218152D01*
G01X686664Y239303D02*
X793230Y216978D01*
G01X686664Y239303D02*
X793230Y216978D01*
G01X686667Y240478D02*
X793238Y218152D01*
G01X726556Y103139D02*
X835920Y80230D01*
G01X726562Y104313D02*
X835926Y81404D01*
G01X726562Y104313D02*
X835926Y81404D01*
G01X726556Y103139D02*
X835920Y80230D01*
G01X719993Y157355D02*
X868731Y186919D01*
G01X719999Y158529D02*
X868506Y188048D01*
G01X719999Y158529D02*
X868506Y188048D01*
G01X719993Y157355D02*
X868731Y186919D01*
G01X748830Y310959D02*
X750743Y311339D01*
G01X748830Y310959D02*
X750743Y311339D01*
G01X752232Y142904D02*
X926252Y177496D01*
G01X752238Y144078D02*
X800667Y153705D01*
G01X752232Y142904D02*
X926252Y177496D01*
G01X752232Y142904D02*
X926252Y177496D01*
G01X752232Y142904D02*
X926252Y177496D01*
G01X752232Y142904D02*
X926252Y177496D01*
G01X752238Y144078D02*
X800667Y153705D01*
G01X752232Y142904D02*
X926252Y177496D01*
G01X773605Y132030D02*
X926503Y161748D01*
G01X773609Y133203D02*
X808204Y139927D01*
G01X773605Y132030D02*
X926503Y161748D01*
G01X773605Y132030D02*
X926503Y161748D01*
G01X773605Y132030D02*
X926503Y161748D01*
G01X773605Y132030D02*
X926503Y161748D01*
G01X773609Y133203D02*
X808204Y139927D01*
G01X773605Y132030D02*
X926503Y161748D01*
G01X794256Y120290D02*
X926514Y145998D01*
G01X794264Y121464D02*
X898482Y141722D01*
G01X794256Y120290D02*
X926514Y145998D01*
G01X794256Y120290D02*
X926514Y145998D01*
G01X794256Y120290D02*
X926514Y145998D01*
G01X794256Y120290D02*
X926514Y145998D01*
G01X794256Y120290D02*
X926514Y145998D01*
G01X794264Y121464D02*
X898482Y141722D01*
G01X794256Y120290D02*
X926514Y145998D01*
G01X796117Y211104D02*
X903544Y232484D01*
G01X796111Y209930D02*
X802173Y211136D01*
G01X789426Y211330D02*
X796111Y209930D01*
G01X784650Y212330D02*
X786558Y211931D01*
G01X796117Y211104D02*
X903544Y232484D01*
G01X796117Y211104D02*
X903544Y232484D01*
G01X796117Y211104D02*
X903544Y232484D01*
G01X796117Y211104D02*
X903544Y232484D01*
G01X796117Y211104D02*
X903544Y232484D01*
G01X796117Y211104D02*
X903544Y232484D01*
G01X796117Y211104D02*
X903544Y232484D01*
G01X796117Y211104D02*
X903544Y232484D01*
G01X796117Y211104D02*
X903544Y232484D01*
G01X796117Y211104D02*
X903544Y232484D01*
G01X796117Y211104D02*
X903544Y232484D01*
G01X796117Y211104D02*
X903544Y232484D01*
G01X796111Y209930D02*
X802173Y211136D01*
G01X796117Y211104D02*
X903544Y232484D01*
G01X789426Y211330D02*
X796111Y209930D01*
G01X784650Y212330D02*
X786558Y211931D01*
G01X780179Y200681D02*
X916193Y227702D01*
G01X780173Y199507D02*
X807966Y205028D01*
G01X780179Y200681D02*
X916193Y227702D01*
G01X780179Y200681D02*
X916193Y227702D01*
G01X780179Y200681D02*
X916193Y227702D01*
G01X780179Y200681D02*
X916193Y227702D01*
G01X780179Y200681D02*
X916193Y227702D01*
G01X780179Y200681D02*
X916193Y227702D01*
G01X780179Y200681D02*
X916193Y227702D01*
G01X780179Y200681D02*
X916193Y227702D01*
G01X780179Y200681D02*
X916193Y227702D01*
G01X780179Y200681D02*
X916193Y227702D01*
G01X780179Y200681D02*
X916193Y227702D01*
G01X780179Y200681D02*
X916193Y227702D01*
G01X780173Y199507D02*
X807966Y205028D01*
G01X780179Y200681D02*
X916193Y227702D01*
G01X795365Y191218D02*
X922335Y216715D01*
G01X795364Y190044D02*
X798322Y190638D01*
G01X786011Y191947D02*
X795364Y190044D01*
G01X781229Y192919D02*
X783140Y192531D01*
G01X795365Y191218D02*
X922335Y216715D01*
G01X795365Y191218D02*
X922335Y216715D01*
G01X795365Y191218D02*
X922335Y216715D01*
G01X795365Y191218D02*
X922335Y216715D01*
G01X795365Y191218D02*
X922335Y216715D01*
G01X795365Y191218D02*
X922335Y216715D01*
G01X795365Y191218D02*
X922335Y216715D01*
G01X795365Y191218D02*
X922335Y216715D01*
G01X795365Y191218D02*
X922335Y216715D01*
G01X795365Y191218D02*
X922335Y216715D01*
G01X795365Y191218D02*
X922335Y216715D01*
G01X795365Y191218D02*
X922335Y216715D01*
G01X795365Y191218D02*
X922335Y216715D01*
G01X795365Y191218D02*
X922335Y216715D01*
G01X795364Y190044D02*
X798322Y190638D01*
G01X795365Y191218D02*
X922335Y216715D01*
G01X786011Y191947D02*
X795364Y190044D01*
G01X781229Y192919D02*
X783140Y192531D01*
G01X779873Y213331D02*
X781782Y212931D01*
G01X779873Y213331D02*
X781782Y212931D01*
G01X793238Y218152D02*
X883671Y235742D01*
G01X793230Y216978D02*
X795144Y217350D01*
G01X793238Y218152D02*
X883671Y235742D01*
G01X793238Y218152D02*
X883671Y235742D01*
G01X793238Y218152D02*
X883671Y235742D01*
G01X793238Y218152D02*
X883671Y235742D01*
G01X793238Y218152D02*
X883671Y235742D01*
G01X793238Y218152D02*
X883671Y235742D01*
G01X793238Y218152D02*
X883671Y235742D01*
G01X793238Y218152D02*
X883671Y235742D01*
G01X793230Y216978D02*
X795144Y217350D01*
G01X793238Y218152D02*
X883671Y235742D01*
G01X793369Y306414D02*
X795282Y306794D01*
G01X788661Y305479D02*
X790574Y305859D01*
G01X793369Y306414D02*
X795282Y306794D01*
G01X788661Y305479D02*
X790574Y305859D01*
G01X789212Y320153D02*
X925418Y296638D01*
G01X793957Y318166D02*
X795879Y317835D01*
G01X789227Y318983D02*
X791149Y318651D01*
G01X781343Y317417D02*
X789227Y318983D01*
G01X776557Y316467D02*
X778469Y316846D01*
G01X771770Y315516D02*
X773683Y315896D01*
G01X758403Y312861D02*
X768896Y314945D01*
G01X753617Y311910D02*
X755529Y312290D01*
G01X789212Y320153D02*
X925418Y296638D01*
G01X789212Y320153D02*
X925418Y296638D01*
G01X789212Y320153D02*
X925418Y296638D01*
G01X789212Y320153D02*
X925418Y296638D01*
G01X789212Y320153D02*
X925418Y296638D01*
G01X789212Y320153D02*
X925418Y296638D01*
G01X789212Y320153D02*
X925418Y296638D01*
G01X789212Y320153D02*
X925418Y296638D01*
G01X793957Y318166D02*
X795879Y317835D01*
G01X789212Y320153D02*
X925418Y296638D01*
G01X789227Y318983D02*
X791149Y318651D01*
G01X789212Y320153D02*
X925418Y296638D01*
G01X781343Y317417D02*
X789227Y318983D01*
G01X776557Y316467D02*
X778469Y316846D01*
G01X771770Y315516D02*
X773683Y315896D01*
G01X758403Y312861D02*
X768896Y314945D01*
G01X753617Y311910D02*
X755529Y312290D01*
G01X795890Y1344028D02*
X1037160Y548885D01*
G01X797079Y1344071D02*
X1035427Y558561D01*
G01X804429Y1381810D02*
X795890Y1344028D01*
G01X805608Y1381807D02*
X797079Y1344071D01*
G01X795890Y1344028D02*
X1037160Y548885D01*
G01X795890Y1344028D02*
X1037160Y548885D01*
G01X797079Y1344071D02*
X1035427Y558561D01*
G01X795890Y1344028D02*
X1037160Y548885D01*
G01X805608Y1381807D02*
X797079Y1344071D01*
G01X804429Y1381810D02*
X795890Y1344028D01*
G01X835360Y88374D02*
X928057Y106512D01*
G01X835359Y89546D02*
X927945Y107662D01*
G01X835359Y89546D02*
X927945Y107662D01*
G01X835360Y88374D02*
X928057Y106512D01*
G01X835926Y81404D02*
X928450Y99788D01*
G01X835920Y80230D02*
X882413Y89468D01*
G01X835926Y81404D02*
X928450Y99788D01*
G01X835926Y81404D02*
X928450Y99788D01*
G01X835920Y80230D02*
X882413Y89468D01*
G01X824416Y103545D02*
X920701Y122260D01*
G01X824416Y104717D02*
X920590Y123410D01*
G01X824416Y104717D02*
X920590Y123410D01*
G01X824416Y103545D02*
X920701Y122260D01*
G01X826157Y96529D02*
X918032Y114386D01*
G01X826157Y97701D02*
X917921Y115536D01*
G01X826157Y97701D02*
X917921Y115536D01*
G01X826157Y96529D02*
X918032Y114386D01*
G01X817586Y157068D02*
X926138Y178646D01*
G01X812878Y156132D02*
X814790Y156513D01*
G01X808170Y155196D02*
X810083Y155577D01*
G01X803462Y154261D02*
X805375Y154641D01*
G01X817586Y157068D02*
X926138Y178646D01*
G01X812878Y156132D02*
X814790Y156513D01*
G01X808170Y155196D02*
X810083Y155577D01*
G01X803462Y154261D02*
X805375Y154641D01*
G01X825137Y143218D02*
X926390Y162898D01*
G01X820425Y142302D02*
X822339Y142674D01*
G01X815713Y141386D02*
X817627Y141759D01*
G01X811001Y140471D02*
X812916Y140843D01*
G01X825137Y143218D02*
X926390Y162898D01*
G01X820425Y142302D02*
X822339Y142674D01*
G01X815713Y141386D02*
X817627Y141759D01*
G01X811001Y140471D02*
X812916Y140843D01*
G01X805046Y211708D02*
X806959Y212089D01*
G01X805046Y211708D02*
X806959Y212089D01*
G01X825199Y208452D02*
X846145Y212613D01*
G01X820413Y207501D02*
X822326Y207881D01*
G01X815626Y206550D02*
X817539Y206930D01*
G01X810840Y205599D02*
X812753Y205979D01*
G01X825199Y208452D02*
X846145Y212613D01*
G01X820413Y207501D02*
X822326Y207881D01*
G01X815626Y206550D02*
X817539Y206930D01*
G01X810840Y205599D02*
X812753Y205979D01*
G01X843979Y199806D02*
X845891Y200190D01*
G01X839273Y198861D02*
X841185Y199245D01*
G01X810764Y193136D02*
X836479Y198300D01*
G01X805979Y192176D02*
X807891Y192559D01*
G01X801195Y191215D02*
X803107Y191599D01*
G01X843979Y199806D02*
X845891Y200190D01*
G01X839273Y198861D02*
X841185Y199245D01*
G01X810764Y193136D02*
X836479Y198300D01*
G01X805979Y192176D02*
X807891Y192559D01*
G01X801195Y191215D02*
X803107Y191599D01*
G01X819405Y214566D02*
X848715Y220398D01*
G01X814619Y213613D02*
X816531Y213994D01*
G01X809832Y212661D02*
X811745Y213041D01*
G01X819405Y214566D02*
X848715Y220398D01*
G01X814619Y213613D02*
X816531Y213994D01*
G01X809832Y212661D02*
X811745Y213041D01*
G01X843558Y226767D02*
X845472Y227140D01*
G01X838768Y225836D02*
X840682Y226208D01*
G01X812391Y220705D02*
X835892Y225276D01*
G01X807601Y219773D02*
X809515Y220146D01*
G01X802810Y218841D02*
X804725Y219214D01*
G01X798020Y217910D02*
X799934Y218282D01*
G01X843558Y226767D02*
X845472Y227140D01*
G01X838768Y225836D02*
X840682Y226208D01*
G01X812391Y220705D02*
X835892Y225276D01*
G01X807601Y219773D02*
X809515Y220146D01*
G01X802810Y218841D02*
X804725Y219214D01*
G01X798020Y217910D02*
X799934Y218282D01*
G01X800003Y308905D02*
X926235Y280890D01*
G01X845408Y297650D02*
X847311Y297227D01*
G01X840722Y298690D02*
X842625Y298267D01*
G01X819046Y303500D02*
X837939Y299307D01*
G01X814282Y304557D02*
X816186Y304135D01*
G01X809518Y305614D02*
X811422Y305192D01*
G01X804754Y306672D02*
X806658Y306249D01*
G01X799990Y307729D02*
X801894Y307307D01*
G01X798077Y307349D02*
X799990Y307729D01*
G01X800003Y308905D02*
X926235Y280890D01*
G01X800003Y308905D02*
X926235Y280890D01*
G01X800003Y308905D02*
X926235Y280890D01*
G01X800003Y308905D02*
X926235Y280890D01*
G01X800003Y308905D02*
X926235Y280890D01*
G01X800003Y308905D02*
X926235Y280890D01*
G01X845408Y297650D02*
X847311Y297227D01*
G01X800003Y308905D02*
X926235Y280890D01*
G01X840722Y298690D02*
X842625Y298267D01*
G01X800003Y308905D02*
X926235Y280890D01*
G01X819046Y303500D02*
X837939Y299307D01*
G01X800003Y308905D02*
X926235Y280890D01*
G01X814282Y304557D02*
X816186Y304135D01*
G01X800003Y308905D02*
X926235Y280890D01*
G01X809518Y305614D02*
X811422Y305192D01*
G01X800003Y308905D02*
X926235Y280890D01*
G01X804754Y306672D02*
X806658Y306249D01*
G01X800003Y308905D02*
X926235Y280890D01*
G01X799990Y307729D02*
X801894Y307307D01*
G01X800003Y308905D02*
X926235Y280890D01*
G01X798077Y307349D02*
X799990Y307729D01*
G01X811061Y338289D02*
X925659Y328134D01*
G01X811126Y337127D02*
X844625Y334159D01*
G01X809215Y336739D02*
X811126Y337128D01*
G01X804433Y335766D02*
X806344Y336155D01*
G01X811061Y338289D02*
X925659Y328134D01*
G01X811061Y338289D02*
X925659Y328134D01*
G01X811061Y338289D02*
X925659Y328134D01*
G01X811061Y338289D02*
X925659Y328134D01*
G01X811061Y338289D02*
X925659Y328134D01*
G01X811061Y338289D02*
X925659Y328134D01*
G01X811061Y338289D02*
X925659Y328134D01*
G01X811061Y338289D02*
X925659Y328134D01*
G01X811126Y337127D02*
X844625Y334159D01*
G01X811061Y338289D02*
X925659Y328134D01*
G01X809215Y336739D02*
X811126Y337128D01*
G01X804433Y335766D02*
X806344Y336155D01*
G01X802367Y329156D02*
X927508Y312386D01*
G01X845370Y322232D02*
X847303Y321973D01*
G01X840533Y322880D02*
X842466Y322621D01*
G01X816914Y326045D02*
X837629Y323269D01*
G01X812077Y326693D02*
X814010Y326434D01*
G01X807241Y327342D02*
X809173Y327083D01*
G01X802404Y327990D02*
X804337Y327731D01*
G01X802367Y329156D02*
X927508Y312386D01*
G01X802367Y329156D02*
X927508Y312386D01*
G01X802367Y329156D02*
X927508Y312386D01*
G01X802367Y329156D02*
X927508Y312386D01*
G01X802367Y329156D02*
X927508Y312386D01*
G01X802367Y329156D02*
X927508Y312386D01*
G01X802367Y329156D02*
X927508Y312386D01*
G01X802367Y329156D02*
X927508Y312386D01*
G01X802367Y329156D02*
X927508Y312386D01*
G01X802367Y329156D02*
X927508Y312386D01*
G01X845370Y322232D02*
X847303Y321973D01*
G01X802367Y329156D02*
X927508Y312386D01*
G01X840533Y322880D02*
X842466Y322621D01*
G01X802367Y329156D02*
X927508Y312386D01*
G01X816914Y326045D02*
X837629Y323269D01*
G01X802367Y329156D02*
X927508Y312386D01*
G01X812077Y326693D02*
X814010Y326434D01*
G01X802367Y329156D02*
X927508Y312386D01*
G01X807241Y327342D02*
X809173Y327083D01*
G01X802367Y329156D02*
X927508Y312386D01*
G01X802404Y327990D02*
X804337Y327731D01*
G01X802367Y329156D02*
X927508Y312386D01*
G01X828650Y312177D02*
X844701Y309406D01*
G01X823920Y312993D02*
X825841Y312662D01*
G01X819190Y313810D02*
X821111Y313478D01*
G01X803417Y316533D02*
X816381Y314295D01*
G01X798687Y317350D02*
X800609Y317018D01*
G01X828650Y312177D02*
X844701Y309406D01*
G01X823920Y312993D02*
X825841Y312662D01*
G01X819190Y313810D02*
X821111Y313478D01*
G01X803417Y316533D02*
X816381Y314295D01*
G01X798687Y317350D02*
X800609Y317018D01*
G01X802699Y1344914D02*
X1027512Y603949D01*
G01X803888Y1344957D02*
X915838Y975983D01*
G01X802699Y1344914D02*
X1027512Y603949D01*
G01X803888Y1344957D02*
X915838Y975983D01*
G01X802699Y1344914D02*
X1027512Y603949D01*
G01X816640Y1349741D02*
X1040109Y613191D01*
G01X817829Y1349784D02*
X1041210Y613524D01*
G01X817829Y1349784D02*
X1041210Y613524D01*
G01X816640Y1349741D02*
X1040109Y613191D01*
G01X809865Y1347998D02*
X1035759Y603457D01*
G01X811054Y1348041D02*
X1035468Y608383D01*
G01X809865Y1347998D02*
X1035759Y603457D01*
G01X811054Y1348041D02*
X1035468Y608383D01*
G01X809865Y1347998D02*
X1035759Y603457D01*
G01X836598Y1352667D02*
X1032521Y706916D01*
G01X836598Y1352667D02*
X1032521Y706916D01*
G01X829986Y1351556D02*
X929921Y1022176D01*
G01X831175Y1351599D02*
X931022Y1022510D01*
G01X831175Y1351599D02*
X931022Y1022510D01*
G01X829986Y1351556D02*
X929921Y1022176D01*
G01X824752Y1351409D02*
X1025868Y687791D01*
G01X823563Y1351366D02*
X924209Y1019267D01*
G01X824752Y1351409D02*
X1025868Y687791D01*
G01X824752Y1351409D02*
X1025868Y687791D01*
G01X823563Y1351366D02*
X924209Y1019267D01*
G01X843271Y1353587D02*
X1027677Y745791D01*
G01X844460Y1353630D02*
X1027386Y750717D01*
G01X850325Y1384800D02*
X843271Y1353587D01*
G01X851501Y1384784D02*
X844460Y1353630D01*
G01X843271Y1353587D02*
X1027677Y745791D01*
G01X844460Y1353630D02*
X1027386Y750717D01*
G01X843271Y1353587D02*
X1027677Y745791D01*
G01X851501Y1384784D02*
X844460Y1353630D01*
G01X850325Y1384800D02*
X843271Y1353587D01*
G01X837787Y1352710D02*
X1033623Y707249D01*
G01X844847Y1383951D02*
X837787Y1352710D01*
G01X843668Y1383954D02*
X836598Y1352667D01*
G01X837787Y1352710D02*
X1033623Y707249D01*
G01X843668Y1383954D02*
X836598Y1352667D01*
G01X844847Y1383951D02*
X837787Y1352710D01*
G01X837213Y1383537D02*
X829986Y1351556D01*
G01X838392Y1383534D02*
X831175Y1351599D01*
G01X838392Y1383534D02*
X831175Y1351599D01*
G01X837213Y1383537D02*
X829986Y1351556D01*
G01X830810Y1383437D02*
X823563Y1351366D01*
G01X831989Y1383434D02*
X824752Y1351409D01*
G01X831989Y1383434D02*
X824752Y1351409D01*
G01X830810Y1383437D02*
X823563Y1351366D01*
G01X824212Y1383247D02*
X816640Y1349741D01*
G01X825391Y1383244D02*
X817829Y1349784D01*
G01X825391Y1383244D02*
X817829Y1349784D01*
G01X824212Y1383247D02*
X816640Y1349741D01*
G01X817715Y1382731D02*
X809865Y1347998D01*
G01X818894Y1382728D02*
X811054Y1348041D01*
G01X818894Y1382728D02*
X811054Y1348041D01*
G01X817715Y1382731D02*
X809865Y1347998D01*
G01X811276Y1382856D02*
X802699Y1344914D01*
G01X812455Y1382853D02*
X803888Y1344957D01*
G01X812455Y1382853D02*
X803888Y1344957D01*
G01X811276Y1382856D02*
X802699Y1344914D01*
G01X845531Y1408961D02*
X850325Y1384800D01*
G01X872634Y1528692D02*
X845531Y1408961D01*
G01D02*
X850325Y1384800D01*
G01X872634Y1528692D02*
X845531Y1408961D01*
G01X839347Y1408780D02*
X844847Y1383951D01*
G01X838168Y1408783D02*
X843668Y1383954D01*
G01X866894Y1530484D02*
X839347Y1408780D01*
G01X865715Y1530487D02*
X838168Y1408783D01*
G01D02*
X843668Y1383954D01*
G01X839347Y1408780D02*
X844847Y1383951D01*
G01X865715Y1530487D02*
X838168Y1408783D01*
G01X866894Y1530484D02*
X839347Y1408780D01*
G01X834312Y1396639D02*
X837213Y1383537D01*
G01X832480Y1410241D02*
X838392Y1383534D01*
G01X831301Y1410244D02*
X834313Y1396639D01*
G01X832480Y1410241D02*
X838392Y1383534D01*
G01X858898Y1532184D02*
X831301Y1410244D01*
G01X860077Y1532181D02*
X832480Y1410241D01*
G01D02*
X838392Y1383534D01*
G01X834312Y1396639D02*
X837213Y1383537D01*
G01X831301Y1410244D02*
X834313Y1396639D01*
G01X860077Y1532181D02*
X832480Y1410241D01*
G01X858898Y1532184D02*
X831301Y1410244D01*
G01X824673Y1411148D02*
X830810Y1383437D01*
G01X825852Y1411145D02*
X831989Y1383434D01*
G01X849204Y1519456D02*
X824673Y1411148D01*
G01X850383Y1519453D02*
X825852Y1411145D01*
G01D02*
X831989Y1383434D01*
G01X824673Y1411148D02*
X830810Y1383437D01*
G01X850383Y1519453D02*
X825852Y1411145D01*
G01X849204Y1519456D02*
X824673Y1411148D01*
G01X821187Y1396905D02*
X824212Y1383247D01*
G01X819231Y1411063D02*
X825391Y1383244D01*
G01X818052Y1411066D02*
X821188Y1396905D01*
G01X819231Y1411063D02*
X825391Y1383244D01*
G01X842516Y1519165D02*
X818052Y1411066D01*
G01X843695Y1519162D02*
X819231Y1411063D01*
G01D02*
X825391Y1383244D01*
G01X821187Y1396905D02*
X824212Y1383247D01*
G01X818052Y1411066D02*
X821188Y1396905D01*
G01X843695Y1519162D02*
X819231Y1411063D01*
G01X842516Y1519165D02*
X818052Y1411066D01*
G01X811402Y1411236D02*
X817715Y1382731D01*
G01X812581Y1411233D02*
X818894Y1382728D01*
G01X833725Y1509852D02*
X811402Y1411236D01*
G01X834904Y1509849D02*
X812581Y1411233D01*
G01D02*
X818894Y1382728D01*
G01X811402Y1411236D02*
X817715Y1382731D01*
G01X834904Y1509849D02*
X812581Y1411233D01*
G01X833725Y1509852D02*
X811402Y1411236D01*
G01X804978Y1411290D02*
X811276Y1382856D01*
G01X806157Y1411287D02*
X812455Y1382853D01*
G01X827241Y1509666D02*
X804978Y1411290D01*
G01X828420Y1509663D02*
X806157Y1411287D01*
G01D02*
X812455Y1382853D01*
G01X804978Y1411290D02*
X811276Y1382856D01*
G01X828420Y1509663D02*
X806157Y1411287D01*
G01X827241Y1509666D02*
X804978Y1411290D01*
G01X798151Y1410160D02*
X804429Y1381810D01*
G01X799330Y1410157D02*
X805608Y1381807D01*
G01X820546Y1509145D02*
X798151Y1410160D01*
G01X821725Y1509142D02*
X799330Y1410157D01*
G01D02*
X805608Y1381807D01*
G01X798151Y1410160D02*
X804429Y1381810D01*
G01X821725Y1509142D02*
X799330Y1410157D01*
G01X820546Y1509145D02*
X798151Y1410160D01*
G01X825796Y1545647D02*
X833725Y1509852D01*
G01X826975Y1545644D02*
X834904Y1509849D01*
G01X826975Y1545644D02*
X834904Y1509849D01*
G01X825796Y1545647D02*
X833725Y1509852D01*
G01X818929Y1547189D02*
X827241Y1509666D01*
G01X820108Y1547186D02*
X828420Y1509663D01*
G01X820108Y1547186D02*
X828420Y1509663D01*
G01X818929Y1547189D02*
X827241Y1509666D01*
G01X811688Y1549138D02*
X820546Y1509145D01*
G01X812867Y1549135D02*
X821725Y1509142D01*
G01X812867Y1549135D02*
X821725Y1509142D01*
G01X811688Y1549138D02*
X820546Y1509145D01*
G01X841872Y1552561D02*
X849204Y1519456D01*
G01X843051Y1552558D02*
X850383Y1519453D01*
G01X851000Y1592923D02*
X841872Y1552561D01*
G01X852150Y1592794D02*
X843051Y1552558D01*
G01D02*
X850383Y1519453D01*
G01X841872Y1552561D02*
X849204Y1519456D01*
G01X852150Y1592794D02*
X843051Y1552558D01*
G01X851000Y1592923D02*
X841872Y1552561D01*
G01X834616Y1554830D02*
X842516Y1519165D01*
G01X835795Y1554827D02*
X843695Y1519162D01*
G01X843914Y1595941D02*
X834616Y1554830D01*
G01X845064Y1595812D02*
X835795Y1554827D01*
G01D02*
X843695Y1519162D01*
G01X834616Y1554830D02*
X842516Y1519165D01*
G01X845064Y1595812D02*
X835795Y1554827D01*
G01X843914Y1595941D02*
X834616Y1554830D01*
G01X836827Y1594395D02*
X825796Y1545647D01*
G01X837977Y1594266D02*
X826975Y1545644D01*
G01X837977Y1594266D02*
X826975Y1545644D01*
G01X836827Y1594395D02*
X825796Y1545647D01*
G01X829741Y1594993D02*
X818929Y1547189D01*
G01X830891Y1594864D02*
X820108Y1547186D01*
G01X830891Y1594864D02*
X820108Y1547186D01*
G01X829741Y1594993D02*
X818929Y1547189D01*
G01X822654Y1597613D02*
X811688Y1549138D01*
G01X823804Y1597484D02*
X812867Y1549135D01*
G01X823804Y1597484D02*
X812867Y1549135D01*
G01X822654Y1597613D02*
X811688Y1549138D01*
G01X843914Y1599820D02*
Y1595941D01*
G01X845064Y1599820D02*
Y1595812D01*
G01X844426Y1601131D02*
G03X843914Y1599820I1424J-1312D01*
G01X845272Y1600352D02*
G03X845064Y1599820I578J-533D01*
G01X845850Y1600606D02*
G03X845272Y1600352I0J-785D01*
G01X845850Y1601756D02*
G03X844426Y1601131I0J-1935D01*
G01X845272Y1600352D02*
G03X845064Y1599820I578J-533D01*
G01X845850Y1600606D02*
G03X845272Y1600352I0J-785D01*
G01X847305Y1601756D02*
X845850D01*
G01X847314Y1600606D02*
X845850D01*
G01X845064Y1599820D02*
Y1595812D01*
G01X843914Y1599820D02*
Y1595941D01*
G01X845272Y1600352D02*
G03X845064Y1599820I578J-533D01*
G01X844426Y1601131D02*
G03X843914Y1599820I1424J-1312D01*
G01X845850Y1601756D02*
G03X844426Y1601131I0J-1935D01*
G01X845850Y1600606D02*
G03X845272Y1600352I0J-785D01*
G01X844426Y1601131D02*
G03X843914Y1599820I1424J-1312D01*
G01X845850Y1601756D02*
G03X844426Y1601131I0J-1935D01*
G01X847314Y1600606D02*
X845850D01*
G01X847305Y1601756D02*
X845850D01*
G01X836827Y1603757D02*
Y1594395D01*
G01X837977Y1603757D02*
Y1594266D01*
G01X838763Y1605693D02*
G03X836827Y1603757I0J-1936D01*
G01X838185Y1604289D02*
G03X837977Y1603757I578J-533D01*
G01X838763Y1604543D02*
G03X838185Y1604289I0J-785D01*
G01X840218Y1605693D02*
X838763D01*
G01X840227Y1604543D02*
X838763D01*
G01X837977Y1603757D02*
Y1594266D01*
G01X836827Y1603757D02*
Y1594395D01*
G01X838185Y1604289D02*
G03X837977Y1603757I578J-533D01*
G01X838763Y1605693D02*
G03X836827Y1603757I0J-1936D01*
G01X838763Y1604543D02*
G03X838185Y1604289I0J-785D01*
G01X838763Y1605693D02*
G03X836827Y1603757I0J-1936D01*
G01X840227Y1604543D02*
X838763D01*
G01X840218Y1605693D02*
X838763D01*
G01X829741Y1599820D02*
Y1594993D01*
G01X830891Y1599820D02*
Y1594864D01*
G01X831677Y1601756D02*
G03X829741Y1599820I0J-1936D01*
G01X831099Y1600352D02*
G03X830891Y1599820I578J-533D01*
G01X831677Y1600606D02*
G03X831099Y1600352I0J-785D01*
G01X833132Y1601756D02*
X831677D01*
G01X833141Y1600606D02*
X831677D01*
G01X830891Y1599820D02*
Y1594864D01*
G01X829741Y1599820D02*
Y1594993D01*
G01X831099Y1600352D02*
G03X830891Y1599820I578J-533D01*
G01X831677Y1601756D02*
G03X829741Y1599820I0J-1936D01*
G01X831677Y1600606D02*
G03X831099Y1600352I0J-785D01*
G01X831677Y1601756D02*
G03X829741Y1599820I0J-1936D01*
G01X833141Y1600606D02*
X831677D01*
G01X833132Y1601756D02*
X831677D01*
G01X822654Y1603758D02*
Y1597613D01*
G01X823804Y1603757D02*
Y1597484D01*
G01X823166Y1605068D02*
G03X822654Y1603758I1424J-1312D01*
G01X824012Y1604289D02*
G03X823804Y1603757I578J-533D01*
G01X824590Y1604543D02*
G03X824012Y1604289I0J-785D01*
G01X824590Y1605693D02*
G03X823166Y1605068I0J-1935D01*
G01X824012Y1604289D02*
G03X823804Y1603757I578J-533D01*
G01X824590Y1604543D02*
G03X824012Y1604289I0J-785D01*
G01X826045Y1605693D02*
X824590D01*
G01X826054Y1604543D02*
X824590D01*
G01X823804Y1603757D02*
Y1597484D01*
G01X822654Y1603758D02*
Y1597613D01*
G01X824012Y1604289D02*
G03X823804Y1603757I578J-533D01*
G01X823166Y1605068D02*
G03X822654Y1603758I1424J-1312D01*
G01X824590Y1605693D02*
G03X823166Y1605068I0J-1935D01*
G01X824590Y1604543D02*
G03X824012Y1604289I0J-785D01*
G01X823166Y1605068D02*
G03X822654Y1603758I1424J-1312D01*
G01X824590Y1605693D02*
G03X823166Y1605068I0J-1935D01*
G01X826054Y1604543D02*
X824590D01*
G01X826045Y1605693D02*
X824590D01*
G01X882413Y89468D02*
X928564Y98638D01*
G01X882413Y89468D02*
X928564Y98638D01*
G01X868730Y186920D02*
X900546Y193244D01*
G01X885425Y191411D02*
X900432Y194394D01*
G01X880717Y190475D02*
X882630Y190856D01*
G01X876009Y189540D02*
X877922Y189920D01*
G01X871301Y188604D02*
X873214Y188984D01*
G01X885425Y191411D02*
X900432Y194394D01*
G01X868730Y186920D02*
X900546Y193244D01*
G01X880717Y190475D02*
X882630Y190856D01*
G01X868730Y186920D02*
X900546Y193244D01*
G01X876009Y189540D02*
X877922Y189920D01*
G01X868730Y186920D02*
X900546Y193244D01*
G01X871301Y188604D02*
X873214Y188984D01*
G01X868730Y186920D02*
X900546Y193244D01*
G01X889912Y209029D02*
X909522Y212967D01*
G01X885206Y208084D02*
X887119Y208469D01*
G01X880500Y207139D02*
X882413Y207524D01*
G01X875794Y206194D02*
X877707Y206579D01*
G01X869244Y204879D02*
X873001Y205634D01*
G01X853391Y201696D02*
X869244Y204879D01*
G01X848685Y200751D02*
X850597Y201135D01*
G01X889912Y209029D02*
X909522Y212967D01*
G01X885206Y208084D02*
X887119Y208469D01*
G01X880500Y207139D02*
X882413Y207524D01*
G01X875794Y206194D02*
X877707Y206579D01*
G01X869244Y204879D02*
X873001Y205634D01*
G01X853391Y201696D02*
X869244Y204879D01*
G01X848685Y200751D02*
X850597Y201135D01*
G01X892751Y229163D02*
X894664Y229543D01*
G01X888043Y228226D02*
X889956Y228606D01*
G01X865633Y223765D02*
X885248Y227669D01*
G01X860925Y222829D02*
X862838Y223209D01*
G01X856218Y221892D02*
X858130Y222272D01*
G01X851510Y220955D02*
X853422Y221335D01*
G01X892751Y229163D02*
X894664Y229543D01*
G01X888043Y228226D02*
X889956Y228606D01*
G01X865633Y223765D02*
X885248Y227669D01*
G01X860925Y222829D02*
X862838Y223209D01*
G01X856218Y221892D02*
X858130Y222272D01*
G01X851510Y220955D02*
X853422Y221335D01*
G01X863065Y215974D02*
X897850Y222885D01*
G01X858357Y215039D02*
X860269Y215419D01*
G01X853649Y214103D02*
X855561Y214483D01*
G01X848941Y213168D02*
X850853Y213548D01*
G01X863065Y215974D02*
X897850Y222885D01*
G01X858357Y215039D02*
X860269Y215419D01*
G01X853649Y214103D02*
X855561Y214483D01*
G01X848941Y213168D02*
X850853Y213548D01*
G01X883671Y235742D02*
X922800Y265142D01*
G01X893385Y241601D02*
X894015Y241512D01*
G01X891826Y240430D02*
X893385Y241601D01*
G01X889547Y238718D02*
X890177Y238628D01*
G01X887988Y237546D02*
X889547Y238718D01*
G01X885710Y235834D02*
X886340Y235745D01*
G01X884151Y234663D02*
X885710Y235834D01*
G01X853139Y228631D02*
X884151Y234663D01*
G01X848349Y227699D02*
X850263Y228071D01*
G01X883671Y235742D02*
X922800Y265142D01*
G01X883671Y235742D02*
X922800Y265142D01*
G01X883671Y235742D02*
X922800Y265142D01*
G01X883671Y235742D02*
X922800Y265142D01*
G01X883671Y235742D02*
X922800Y265142D01*
G01X883671Y235742D02*
X922800Y265142D01*
G01X883671Y235742D02*
X922800Y265142D01*
G01X883671Y235742D02*
X922800Y265142D01*
G01X883671Y235742D02*
X922800Y265142D01*
G01X893385Y241601D02*
X894015Y241512D01*
G01X883671Y235742D02*
X922800Y265142D01*
G01X891826Y240430D02*
X893385Y241601D01*
G01X883671Y235742D02*
X922800Y265142D01*
G01X889547Y238718D02*
X890177Y238628D01*
G01X883671Y235742D02*
X922800Y265142D01*
G01X887988Y237546D02*
X889547Y238718D01*
G01X883671Y235742D02*
X922800Y265142D01*
G01X885710Y235834D02*
X886340Y235745D01*
G01X883671Y235742D02*
X922800Y265142D01*
G01X884151Y234663D02*
X885710Y235834D01*
G01X883671Y235742D02*
X922800Y265142D01*
G01X853139Y228631D02*
X884151Y234663D01*
G01X848349Y227699D02*
X850263Y228071D01*
G01X856970Y307288D02*
X925319Y295488D01*
G01X852240Y308104D02*
X854161Y307773D01*
G01X847510Y308921D02*
X849431Y308589D01*
G01X856970Y307288D02*
X925319Y295488D01*
G01X852240Y308104D02*
X854161Y307773D01*
G01X847510Y308921D02*
X849431Y308589D01*
G01X886687Y288489D02*
X903374Y284785D01*
G01X881923Y289546D02*
X883827Y289124D01*
G01X877159Y290603D02*
X879063Y290181D01*
G01X850094Y296610D02*
X874299Y291238D01*
G01X886687Y288489D02*
X903374Y284785D01*
G01X881923Y289546D02*
X883827Y289124D01*
G01X877159Y290603D02*
X879063Y290181D01*
G01X850094Y296610D02*
X874299Y291238D01*
G01X890116Y330128D02*
X892059Y329956D01*
G01X862126Y332608D02*
X887278Y330380D01*
G01X857265Y333039D02*
X859207Y332867D01*
G01X852404Y333470D02*
X854346Y333298D01*
G01X847543Y333900D02*
X849485Y333728D01*
G01X890116Y330128D02*
X892059Y329956D01*
G01X862126Y332608D02*
X887278Y330380D01*
G01X857265Y333039D02*
X859207Y332867D01*
G01X852404Y333470D02*
X854346Y333298D01*
G01X847543Y333900D02*
X849485Y333728D01*
G01X888578Y316442D02*
X908401Y313786D01*
G01X883821Y317080D02*
X885753Y316821D01*
G01X879063Y317717D02*
X880996Y317458D01*
G01X874306Y318355D02*
X876239Y318096D01*
G01X855044Y320936D02*
X871481Y318733D01*
G01X850207Y321584D02*
X852140Y321325D01*
G01X888578Y316442D02*
X908401Y313786D01*
G01X883821Y317080D02*
X885753Y316821D01*
G01X879063Y317717D02*
X880996Y317458D01*
G01X874306Y318355D02*
X876239Y318096D01*
G01X855044Y320936D02*
X871481Y318733D01*
G01X850207Y321584D02*
X852140Y321325D01*
G01X898350Y400960D02*
X867644Y558918D01*
G01X897265Y400511D02*
X866472Y558918D01*
G01X897265Y400511D02*
X866472Y558918D01*
G01X898350Y400960D02*
X867644Y558918D01*
G01X904531Y400897D02*
X873378Y561153D01*
G01X904531Y400897D02*
X873378Y561153D01*
G01X911461Y404046D02*
X881151Y559962D01*
G01X910376Y403597D02*
X879979Y559962D01*
G01X910376Y403597D02*
X879979Y559962D01*
G01X911461Y404046D02*
X881151Y559962D01*
G01X905616Y401346D02*
X874550Y561153D01*
G01X905616Y401346D02*
X874550Y561153D01*
G01X917980Y406228D02*
X888005Y560376D01*
G01X916895Y405778D02*
X886833Y560376D01*
G01X916895Y405778D02*
X886833Y560376D01*
G01X917980Y406228D02*
X888005Y560376D01*
G01X881151Y559962D02*
X892112Y616348D01*
G01X879979Y559962D02*
X891027Y616797D01*
G01X879979Y559962D02*
X891027Y616797D01*
G01X881151Y559962D02*
X892112Y616348D01*
G01X892574Y583880D02*
X897142Y607382D01*
G01X886833Y560376D02*
X896057Y607831D01*
G01X888005Y560376D02*
X892574Y583880D01*
G01X886833Y560376D02*
X896057Y607831D01*
G01X886833Y560376D02*
X896057Y607831D01*
G01X892574Y583880D02*
X897142Y607382D01*
G01X888005Y560376D02*
X892574Y583880D01*
G01X867644Y558918D02*
X881975Y632658D01*
G01X866472Y558918D02*
X880890Y633107D01*
G01X866472Y558918D02*
X880890Y633107D01*
G01X867644Y558918D02*
X881975Y632658D01*
G01X874550Y561153D02*
X886652Y623418D01*
G01X873378Y561153D02*
X885567Y623867D01*
G01X873378Y561153D02*
X885567Y623867D01*
G01X874550Y561153D02*
X886652Y623418D01*
G01X892112Y616348D02*
X924588Y664500D01*
G01X891027Y616797D02*
X912224Y648226D01*
G01X892112Y616348D02*
X924588Y664500D01*
G01X892112Y616348D02*
X924588Y664500D01*
G01X892112Y616348D02*
X924588Y664500D01*
G01X892112Y616348D02*
X924588Y664500D01*
G01X892112Y616348D02*
X924588Y664500D01*
G01X891027Y616797D02*
X912224Y648226D01*
G01X892112Y616348D02*
X924588Y664500D01*
G01X881975Y632658D02*
X924808Y696166D01*
G01X880890Y633107D02*
X911739Y678847D01*
G01X881975Y632658D02*
X924808Y696166D01*
G01X881975Y632658D02*
X924808Y696166D01*
G01X881975Y632658D02*
X924808Y696166D01*
G01X881975Y632658D02*
X924808Y696166D01*
G01X880890Y633107D02*
X911739Y678847D01*
G01X881975Y632658D02*
X924808Y696166D01*
G01X886652Y623418D02*
X925409Y680881D01*
G01X885567Y623867D02*
X912316Y663526D01*
G01X886652Y623418D02*
X925409Y680881D01*
G01X886652Y623418D02*
X925409Y680881D01*
G01X886652Y623418D02*
X925409Y680881D01*
G01X886652Y623418D02*
X925409Y680881D01*
G01X885567Y623867D02*
X912316Y663526D01*
G01X886652Y623418D02*
X925409Y680881D01*
G01X846707Y1408945D02*
X851501Y1384784D01*
G01X873813Y1528689D02*
X846707Y1408945D01*
G01D02*
X851501Y1384784D01*
G01X873813Y1528689D02*
X846707Y1408945D01*
G01X865176Y1562372D02*
X872634Y1528692D01*
G01X866355Y1562369D02*
X873813Y1528689D01*
G01X872260Y1593691D02*
X865176Y1562372D01*
G01X873410Y1593562D02*
X866355Y1562369D01*
G01D02*
X873813Y1528689D01*
G01X865176Y1562372D02*
X872634Y1528692D01*
G01X873410Y1593562D02*
X866355Y1562369D01*
G01X872260Y1593691D02*
X865176Y1562372D01*
G01X859758Y1562687D02*
X866894Y1530484D01*
G01X858578Y1562692D02*
X865715Y1530487D01*
G01X866324Y1591245D02*
X859758Y1562687D01*
G01X865174Y1591376D02*
X858578Y1562692D01*
G01D02*
X865715Y1530487D01*
G01X859758Y1562687D02*
X866894Y1530484D01*
G01X865174Y1591376D02*
X858578Y1562692D01*
G01X866324Y1591245D02*
X859758Y1562687D01*
G01X851637Y1564964D02*
X858898Y1532184D01*
G01X852816Y1564961D02*
X860077Y1532181D01*
G01X858087Y1593456D02*
X851637Y1564964D01*
G01X859237Y1593327D02*
X852816Y1564961D01*
G01D02*
X860077Y1532181D01*
G01X851637Y1564964D02*
X858898Y1532184D01*
G01X859237Y1593327D02*
X852816Y1564961D01*
G01X858087Y1593456D02*
X851637Y1564964D01*
G01X872260Y1599820D02*
Y1593691D01*
G01X873410Y1599820D02*
Y1593562D01*
G01X872772Y1601131D02*
G03X872260Y1599820I1424J-1312D01*
G01X873618Y1600352D02*
G03X873410Y1599820I578J-533D01*
G01X874196Y1600606D02*
G03X873618Y1600352I0J-785D01*
G01X874196Y1601756D02*
G03X872772Y1601131I0J-1935D01*
G01X873618Y1600352D02*
G03X873410Y1599820I578J-533D01*
G01X874196Y1600606D02*
G03X873618Y1600352I0J-785D01*
G01X875651Y1601756D02*
X874196D01*
G01X875660Y1600606D02*
X874196D01*
G01X873410Y1599820D02*
Y1593562D01*
G01X872260Y1599820D02*
Y1593691D01*
G01X873618Y1600352D02*
G03X873410Y1599820I578J-533D01*
G01X872772Y1601131D02*
G03X872260Y1599820I1424J-1312D01*
G01X874196Y1601756D02*
G03X872772Y1601131I0J-1935D01*
G01X874196Y1600606D02*
G03X873618Y1600352I0J-785D01*
G01X872772Y1601131D02*
G03X872260Y1599820I1424J-1312D01*
G01X874196Y1601756D02*
G03X872772Y1601131I0J-1935D01*
G01X875660Y1600606D02*
X874196D01*
G01X875651Y1601756D02*
X874196D01*
G01X866324Y1603757D02*
Y1591245D01*
G01X865174Y1603757D02*
Y1591376D01*
G01X866532Y1604289D02*
G03X866324Y1603757I578J-533D01*
G01X865686Y1605068D02*
G03X865174Y1603757I1424J-1312D01*
G01X867110Y1605693D02*
G03X865686Y1605068I0J-1935D01*
G01X867110Y1604543D02*
G03X866532Y1604289I0J-785D01*
G01X865686Y1605068D02*
G03X865174Y1603757I1424J-1312D01*
G01X867110Y1605693D02*
G03X865686Y1605068I0J-1935D01*
G01X868574Y1604543D02*
X867110D01*
G01X868565Y1605693D02*
X867110D01*
G01X865174Y1603757D02*
Y1591376D01*
G01X866324Y1603757D02*
Y1591245D01*
G01X865686Y1605068D02*
G03X865174Y1603757I1424J-1312D01*
G01X866532Y1604289D02*
G03X866324Y1603757I578J-533D01*
G01X867110Y1604543D02*
G03X866532Y1604289I0J-785D01*
G01X867110Y1605693D02*
G03X865686Y1605068I0J-1935D01*
G01X866532Y1604289D02*
G03X866324Y1603757I578J-533D01*
G01X867110Y1604543D02*
G03X866532Y1604289I0J-785D01*
G01X868565Y1605693D02*
X867110D01*
G01X868574Y1604543D02*
X867110D01*
G01X858087Y1599820D02*
Y1593456D01*
G01X859237Y1599820D02*
Y1593327D01*
G01X860023Y1601756D02*
G03X858087Y1599820I0J-1936D01*
G01X859445Y1600352D02*
G03X859237Y1599820I578J-533D01*
G01X860023Y1600606D02*
G03X859445Y1600352I0J-785D01*
G01X861478Y1601756D02*
X860023D01*
G01X861487Y1600606D02*
X860023D01*
G01X859237Y1599820D02*
Y1593327D01*
G01X858087Y1599820D02*
Y1593456D01*
G01X859445Y1600352D02*
G03X859237Y1599820I578J-533D01*
G01X860023Y1601756D02*
G03X858087Y1599820I0J-1936D01*
G01X860023Y1600606D02*
G03X859445Y1600352I0J-785D01*
G01X860023Y1601756D02*
G03X858087Y1599820I0J-1936D01*
G01X861487Y1600606D02*
X860023D01*
G01X861478Y1601756D02*
X860023D01*
G01X851000Y1603757D02*
Y1592923D01*
G01X852150Y1603757D02*
Y1592794D01*
G01X851512Y1605068D02*
G03X851000Y1603757I1424J-1312D01*
G01X852358Y1604289D02*
G03X852150Y1603757I578J-533D01*
G01X852936Y1604543D02*
G03X852358Y1604289I0J-785D01*
G01X852936Y1605693D02*
G03X851512Y1605068I0J-1935D01*
G01X852358Y1604289D02*
G03X852150Y1603757I578J-533D01*
G01X852936Y1604543D02*
G03X852358Y1604289I0J-785D01*
G01X854391Y1605693D02*
X852936D01*
G01X854400Y1604543D02*
X852936D01*
G01X852150Y1603757D02*
Y1592794D01*
G01X851000Y1603757D02*
Y1592923D01*
G01X852358Y1604289D02*
G03X852150Y1603757I578J-533D01*
G01X851512Y1605068D02*
G03X851000Y1603757I1424J-1312D01*
G01X852936Y1605693D02*
G03X851512Y1605068I0J-1935D01*
G01X852936Y1604543D02*
G03X852358Y1604289I0J-785D01*
G01X851512Y1605068D02*
G03X851000Y1603757I1424J-1312D01*
G01X852936Y1605693D02*
G03X851512Y1605068I0J-1935D01*
G01X854400Y1604543D02*
X852936D01*
G01X854391Y1605693D02*
X852936D01*
G01X935139Y110449D02*
X948917D01*
G01X934662Y111599D02*
X948441D01*
G01X931202Y106512D02*
X935139Y110449D01*
G01X930725Y107662D02*
X934662Y111599D01*
G01X928057Y106512D02*
X931202D01*
G01X927945Y107662D02*
X930725D01*
G01X934662Y111599D02*
X948441D01*
G01X935139Y110449D02*
X948917D01*
G01X930725Y107662D02*
X934662Y111599D01*
G01X931202Y106512D02*
X935139Y110449D01*
G01X927945Y107662D02*
X930725D01*
G01X928057Y106512D02*
X931202D01*
G01X935138Y102575D02*
X948918D01*
G01X934661Y103725D02*
X948441D01*
G01X931201Y98638D02*
X935138Y102575D01*
G01X930724Y99788D02*
X934661Y103725D01*
G01X928564Y98638D02*
X931201D01*
G01X928450Y99788D02*
X930724D01*
G01X934661Y103725D02*
X948441D01*
G01X935138Y102575D02*
X948918D01*
G01X930724Y99788D02*
X934661Y103725D01*
G01X931201Y98638D02*
X935138Y102575D01*
G01X928450Y99788D02*
X930724D01*
G01X928564Y98638D02*
X931201D01*
G01Y114386D02*
X935138Y118323D01*
G01X930724Y115536D02*
X934661Y119473D01*
G01X918032Y114386D02*
X931201D01*
G01X917921Y115536D02*
X930724D01*
G01D02*
X934661Y119473D01*
G01X931201Y114386D02*
X935138Y118323D01*
G01X917921Y115536D02*
X930724D01*
G01X918032Y114386D02*
X931201D01*
G01X932572Y162539D02*
X933379Y163346D01*
G01X931758Y163353D02*
X932156Y163751D01*
G01X931962Y162081D02*
G03X932572Y162539I-1301J2367D01*
G01X931408Y163090D02*
G03X931758Y163353I-747J1358D01*
G01X930663Y162898D02*
G03X931408Y163090I-2J1551D01*
G01X930662Y161748D02*
G03X931962Y162081I1J2701D01*
G01X931408Y163090D02*
G03X931758Y163353I-747J1358D01*
G01X930663Y162898D02*
G03X931408Y163090I-2J1551D01*
G01X926503Y161748D02*
X930662D01*
G01X926390Y162898D02*
X930663D01*
G01X931758Y163353D02*
X932156Y163751D01*
G01X932572Y162539D02*
X933379Y163346D01*
G01X931408Y163090D02*
G03X931758Y163353I-747J1358D01*
G01X931962Y162081D02*
G03X932572Y162539I-1301J2367D01*
G01X930662Y161748D02*
G03X931962Y162081I1J2701D01*
G01X930663Y162898D02*
G03X931408Y163090I-2J1551D01*
G01X931962Y162081D02*
G03X932572Y162539I-1301J2367D01*
G01X930662Y161748D02*
G03X931962Y162081I1J2701D01*
G01X926390Y162898D02*
X930663D01*
G01X926503Y161748D02*
X930662D01*
G01X932572Y146791D02*
X933379Y147598D01*
G01X931758Y147605D02*
X932156Y148003D01*
G01X931962Y146333D02*
G03X932572Y146791I-1301J2367D01*
G01X931408Y147342D02*
G03X931758Y147605I-747J1358D01*
G01X930663Y147150D02*
G03X931408Y147342I-2J1551D01*
G01X930662Y146000D02*
G03X931962Y146333I1J2701D01*
G01X931408Y147342D02*
G03X931758Y147605I-747J1358D01*
G01X930663Y147150D02*
G03X931408Y147342I-2J1551D01*
G01X926522Y146000D02*
X930662D01*
G01X926407Y147150D02*
X930663D01*
G01X926298Y147129D02*
X926407Y147150D01*
G01X926294Y147128D02*
X926298Y147129D01*
G01X926517Y145999D02*
X926522Y146000D01*
G01X915416Y145014D02*
X926294Y147128D01*
G01X926298Y147129D02*
X926407Y147150D01*
G01X915416Y145014D02*
X926294Y147128D01*
G01X910704Y144098D02*
X912618Y144470D01*
G01X905992Y143182D02*
X907906Y143554D01*
G01X901280Y142266D02*
X903195Y142638D01*
G01X931758Y147605D02*
X932156Y148003D01*
G01X932572Y146791D02*
X933379Y147598D01*
G01X931408Y147342D02*
G03X931758Y147605I-747J1358D01*
G01X931962Y146333D02*
G03X932572Y146791I-1301J2367D01*
G01X930662Y146000D02*
G03X931962Y146333I1J2701D01*
G01X930663Y147150D02*
G03X931408Y147342I-2J1551D01*
G01X931962Y146333D02*
G03X932572Y146791I-1301J2367D01*
G01X930662Y146000D02*
G03X931962Y146333I1J2701D01*
G01X926407Y147150D02*
X930663D01*
G01X926522Y146000D02*
X930662D01*
G01X926298Y147129D02*
X926407Y147150D01*
G01X926522Y146000D02*
X930662D01*
G01X926294Y147128D02*
X926298Y147129D01*
G01X926522Y146000D02*
X930662D01*
G01X915416Y145014D02*
X926294Y147128D01*
G01X926517Y145999D02*
X926522Y146000D01*
G01X910704Y144098D02*
X912618Y144470D01*
G01X905992Y143182D02*
X907906Y143554D01*
G01X901280Y142266D02*
X903195Y142638D01*
G01X935138Y126197D02*
X948918D01*
G01X934661Y127347D02*
X948441D01*
G01X931201Y122260D02*
X935138Y126197D01*
G01X930724Y123410D02*
X934661Y127347D01*
G01X920701Y122260D02*
X931201D01*
G01X920590Y123410D02*
X930724D01*
G01X934661Y127347D02*
X948441D01*
G01X935138Y126197D02*
X948918D01*
G01X930724Y123410D02*
X934661Y127347D01*
G01X931201Y122260D02*
X935138Y126197D01*
G01X920590Y123410D02*
X930724D01*
G01X920701Y122260D02*
X931201D01*
G01X935138Y118323D02*
X948917D01*
G01X934661Y119473D02*
X948440D01*
G01X934661D02*
X948440D01*
G01X935138Y118323D02*
X948917D01*
G01X932572Y194035D02*
X933379Y194842D01*
G01X931758Y194849D02*
X932156Y195247D01*
G01X931962Y193577D02*
G03X932572Y194035I-1301J2367D01*
G01X931408Y194586D02*
G03X931758Y194849I-747J1358D01*
G01X930663Y194394D02*
G03X931408Y194586I-2J1551D01*
G01X930662Y193244D02*
G03X931962Y193577I1J2701D01*
G01X931408Y194586D02*
G03X931758Y194849I-747J1358D01*
G01X930663Y194394D02*
G03X931408Y194586I-2J1551D01*
G01X900546Y193244D02*
X930662D01*
G01X900432Y194394D02*
X930663D01*
G01X931758Y194849D02*
X932156Y195247D01*
G01X932572Y194035D02*
X933379Y194842D01*
G01X931408Y194586D02*
G03X931758Y194849I-747J1358D01*
G01X931962Y193577D02*
G03X932572Y194035I-1301J2367D01*
G01X930662Y193244D02*
G03X931962Y193577I1J2701D01*
G01X930663Y194394D02*
G03X931408Y194586I-2J1551D01*
G01X931962Y193577D02*
G03X932572Y194035I-1301J2367D01*
G01X930662Y193244D02*
G03X931962Y193577I1J2701D01*
G01X900432Y194394D02*
X930663D01*
G01X900546Y193244D02*
X930662D01*
G01X932572Y178287D02*
X933379Y179094D01*
G01X931758Y179101D02*
X932156Y179499D01*
G01X931962Y177829D02*
G03X932572Y178287I-1301J2367D01*
G01X931408Y178838D02*
G03X931758Y179101I-747J1358D01*
G01X930663Y178646D02*
G03X931408Y178838I-2J1551D01*
G01X930662Y177496D02*
G03X931962Y177829I1J2701D01*
G01X931408Y178838D02*
G03X931758Y179101I-747J1358D01*
G01X930663Y178646D02*
G03X931408Y178838I-2J1551D01*
G01X926252Y177496D02*
X930662D01*
G01X926138Y178646D02*
X930663D01*
G01X931758Y179101D02*
X932156Y179499D01*
G01X932572Y178287D02*
X933379Y179094D01*
G01X931408Y178838D02*
G03X931758Y179101I-747J1358D01*
G01X931962Y177829D02*
G03X932572Y178287I-1301J2367D01*
G01X930662Y177496D02*
G03X931962Y177829I1J2701D01*
G01X930663Y178646D02*
G03X931408Y178838I-2J1551D01*
G01X931962Y177829D02*
G03X932572Y178287I-1301J2367D01*
G01X930662Y177496D02*
G03X931962Y177829I1J2701D01*
G01X926138Y178646D02*
X930663D01*
G01X926252Y177496D02*
X930662D01*
G01X934379Y211840D02*
X934380D01*
G01X933795Y212883D02*
X933157Y212245D01*
G01X934842Y212303D02*
X934379Y211840D01*
G01X933795Y212883D02*
X933157Y212245D01*
G01X933795Y212883D02*
X933157Y212245D01*
G01X934379Y211840D02*
X934380D01*
G01X934842Y212303D02*
X934379Y211840D01*
G01Y243336D02*
X934380D01*
G01X933795Y244379D02*
X933157Y243741D01*
G01X934842Y243799D02*
X934379Y243336D01*
G01X933795Y244379D02*
X933157Y243741D01*
G01X935135Y245634D02*
Y244506D01*
G01X933985Y245302D02*
Y244838D01*
G01X932751Y248433D02*
X934842Y246341D01*
G01X932865Y246690D02*
X933794Y245761D01*
G01X931937Y247619D02*
X932865Y246690D01*
G01X930806Y249238D02*
G02X932751Y248433I0J-2752D01*
G01X930806Y248088D02*
G02X931937Y247619I-1J-1601D01*
G01X925294Y249238D02*
X930806D01*
G01X925686Y248088D02*
X930806D01*
G01X903544Y232484D02*
X925294Y249238D01*
G01X904033Y231408D02*
X925686Y248088D01*
G01X902167Y231036D02*
X904033Y231408D01*
G01X897459Y230099D02*
X899371Y230480D01*
G01X933795Y244379D02*
X933157Y243741D01*
G01X934379Y243336D02*
X934380D01*
G01X934842Y243799D02*
X934379Y243336D01*
G01X933985Y245302D02*
Y244838D01*
G01X935135Y245634D02*
Y244506D01*
G01X932865Y246690D02*
X933794Y245761D01*
G01X932751Y248433D02*
X934842Y246341D01*
G01X931937Y247619D02*
X932865Y246690D01*
G01X932751Y248433D02*
X934842Y246341D01*
G01X930806Y248088D02*
G02X931937Y247619I-1J-1601D01*
G01X930806Y249238D02*
G02X932751Y248433I0J-2752D01*
G01X925686Y248088D02*
X930806D01*
G01X925294Y249238D02*
X930806D01*
G01X904033Y231408D02*
X925686Y248088D01*
G01X903544Y232484D02*
X925294Y249238D01*
G01X902167Y231036D02*
X904033Y231408D01*
G01X897459Y230099D02*
X899371Y230480D01*
G01X934379Y227588D02*
X934380D01*
G01X933795Y228631D02*
X933157Y227993D01*
G01X934842Y228051D02*
X934379Y227588D01*
G01X933795Y228631D02*
X933157Y227993D01*
G01X935135Y229886D02*
Y228758D01*
G01X933985Y229554D02*
Y229090D01*
G01X932751Y232685D02*
X934842Y230593D01*
G01X931937Y231871D02*
X933795Y230013D01*
G01X930806Y233490D02*
G02X932751Y232685I0J-2752D01*
G01X930805Y232340D02*
G02X931937Y231871I0J-1601D01*
G01X923707Y233490D02*
X930806D01*
G01X924099Y232340D02*
X930805D01*
G01X916193Y227702D02*
X923707Y233490D01*
G01X916682Y226626D02*
X924099Y232340D01*
G01X914769Y226246D02*
X916682Y226626D01*
G01X910061Y225311D02*
X911974Y225691D01*
G01X905353Y224375D02*
X907266Y224755D01*
G01X900645Y223440D02*
X902558Y223820D01*
G01X933795Y228631D02*
X933157Y227993D01*
G01X934379Y227588D02*
X934380D01*
G01X934842Y228051D02*
X934379Y227588D01*
G01X933985Y229554D02*
Y229090D01*
G01X935135Y229886D02*
Y228758D01*
G01X931937Y231871D02*
X933795Y230013D01*
G01X932751Y232685D02*
X934842Y230593D01*
G01X930805Y232340D02*
G02X931937Y231871I0J-1601D01*
G01X930806Y233490D02*
G02X932751Y232685I0J-2752D01*
G01X924099Y232340D02*
X930805D01*
G01X923707Y233490D02*
X930806D01*
G01X916682Y226626D02*
X924099Y232340D01*
G01X916193Y227702D02*
X923707Y233490D01*
G01X914769Y226246D02*
X916682Y226626D01*
G01X910061Y225311D02*
X911974Y225691D01*
G01X905353Y224375D02*
X907266Y224755D01*
G01X900645Y223440D02*
X902558Y223820D01*
G01X935135Y214138D02*
Y213010D01*
G01X933985Y213806D02*
Y213342D01*
G01X932751Y216937D02*
X934842Y214845D01*
G01X931937Y216123D02*
X933795Y214265D01*
G01X930806Y217742D02*
G02X932751Y216937I0J-2752D01*
G01X930807Y216592D02*
G02X931937Y216123I-2J-1601D01*
G01X924435Y217742D02*
X930806D01*
G01X924702Y216592D02*
X930807D01*
G01X922335Y216715D02*
X924435Y217742D01*
G01X922707Y215616D02*
X924702Y216592D01*
G01X917021Y214473D02*
X922707Y215616D01*
G01X912315Y213528D02*
X914228Y213912D01*
G01X933985Y213806D02*
Y213342D01*
G01X935135Y214138D02*
Y213010D01*
G01X931937Y216123D02*
X933795Y214265D01*
G01X932751Y216937D02*
X934842Y214845D01*
G01X930807Y216592D02*
G02X931937Y216123I-2J-1601D01*
G01X930806Y217742D02*
G02X932751Y216937I0J-2752D01*
G01X924702Y216592D02*
X930807D01*
G01X924435Y217742D02*
X930806D01*
G01X922707Y215616D02*
X924702Y216592D01*
G01X922335Y216715D02*
X924435Y217742D01*
G01X917021Y214473D02*
X922707Y215616D01*
G01X912315Y213528D02*
X914228Y213912D01*
G01X934379Y259084D02*
X934380D01*
G01X933795Y260127D02*
X933157Y259489D01*
G01X934842Y259547D02*
X934379Y259084D01*
G01X933795Y260127D02*
X933157Y259489D01*
G01X935135Y261382D02*
Y260254D01*
G01X933985Y261050D02*
Y260586D01*
G01X917832Y259971D02*
X918462Y259881D01*
G01X916273Y258799D02*
X917832Y259971D01*
G01X913995Y257087D02*
X914625Y256998D01*
G01X912436Y255916D02*
X913995Y257087D01*
G01X910157Y254204D02*
X910787Y254114D01*
G01X899501Y246197D02*
X910157Y254204D01*
G01X897222Y244485D02*
X897852Y244395D01*
G01X895663Y243313D02*
X897222Y244485D01*
G01X933795Y260127D02*
X933157Y259489D01*
G01X934379Y259084D02*
X934380D01*
G01X934842Y259547D02*
X934379Y259084D01*
G01X933985Y261050D02*
Y260586D01*
G01X935135Y261382D02*
Y260254D01*
G01X917832Y259971D02*
X918462Y259881D01*
G01X916273Y258799D02*
X917832Y259971D01*
G01X913995Y257087D02*
X914625Y256998D01*
G01X912436Y255916D02*
X913995Y257087D01*
G01X910157Y254204D02*
X910787Y254114D01*
G01X899501Y246197D02*
X910157Y254204D01*
G01X897222Y244485D02*
X897852Y244395D01*
G01X895663Y243313D02*
X897222Y244485D01*
G01X934379Y306328D02*
X934380D01*
G01X933795Y307371D02*
X933157Y306733D01*
G01X934842Y306791D02*
X934379Y306328D01*
G01X933795Y307371D02*
X933157Y306733D01*
G01X935135Y308626D02*
Y307498D01*
G01X933985Y308294D02*
Y307830D01*
G01X932751Y311425D02*
X934842Y309333D01*
G01X931937Y310611D02*
X933795Y308753D01*
G01Y307371D02*
X933157Y306733D01*
G01X934379Y306328D02*
X934380D01*
G01X934842Y306791D02*
X934379Y306328D01*
G01X933985Y308294D02*
Y307830D01*
G01X935135Y308626D02*
Y307498D01*
G01X931937Y310611D02*
X933795Y308753D01*
G01X932751Y311425D02*
X934842Y309333D01*
G01X934379Y290580D02*
X934380D01*
G01X933795Y291623D02*
X933157Y290985D01*
G01X934842Y291043D02*
X934379Y290580D01*
G01X933795Y291623D02*
X933157Y290985D01*
G01X935135Y292878D02*
Y291750D01*
G01X933985Y292546D02*
Y292082D01*
G01X932751Y295677D02*
X934842Y293585D01*
G01X931937Y294863D02*
X933795Y293005D01*
G01X930431Y296638D02*
G02X932751Y295677I0J-3281D01*
G01X930430Y295488D02*
G02X931937Y294863I0J-2130D01*
G01X925418Y296638D02*
X930431D01*
G01X925319Y295488D02*
X930430D01*
G01X933795Y291623D02*
X933157Y290985D01*
G01X934379Y290580D02*
X934380D01*
G01X934842Y291043D02*
X934379Y290580D01*
G01X933985Y292546D02*
Y292082D01*
G01X935135Y292878D02*
Y291750D01*
G01X931937Y294863D02*
X933795Y293005D01*
G01X932751Y295677D02*
X934842Y293585D01*
G01X930430Y295488D02*
G02X931937Y294863I0J-2130D01*
G01X930431Y296638D02*
G02X932751Y295677I0J-3281D01*
G01X925319Y295488D02*
X930430D01*
G01X925418Y296638D02*
X930431D01*
G01X934379Y274832D02*
X934380D01*
G01X933795Y275875D02*
X933157Y275237D01*
G01X934842Y275295D02*
X934379Y274832D01*
G01X933795Y275875D02*
X933157Y275237D01*
G01X935135Y277130D02*
Y276002D01*
G01X933985Y276798D02*
Y276334D01*
G01X932751Y279929D02*
X934842Y277837D01*
G01X931937Y279115D02*
X933795Y277257D01*
G01X930431Y280890D02*
G02X932751Y279929I0J-3281D01*
G01X930430Y279740D02*
G02X931937Y279115I0J-2130D01*
G01X926235Y280890D02*
X930431D01*
G01X926108Y279740D02*
X930430D01*
G01X910842Y283128D02*
X926108Y279740D01*
G01X906156Y284168D02*
X908060Y283745D01*
G01X933795Y275875D02*
X933157Y275237D01*
G01X934379Y274832D02*
X934380D01*
G01X934842Y275295D02*
X934379Y274832D01*
G01X933985Y276798D02*
Y276334D01*
G01X935135Y277130D02*
Y276002D01*
G01X931937Y279115D02*
X933795Y277257D01*
G01X932751Y279929D02*
X934842Y277837D01*
G01X930430Y279740D02*
G02X931937Y279115I0J-2130D01*
G01X930431Y280890D02*
G02X932751Y279929I0J-3281D01*
G01X926108Y279740D02*
X930430D01*
G01X926235Y280890D02*
X930431D01*
G01X910842Y283128D02*
X926108Y279740D01*
G01X906156Y284168D02*
X908060Y283745D01*
G01X932427Y264505D02*
X934842Y262089D01*
G01X931613Y263691D02*
X933795Y261509D01*
G01X930897Y265142D02*
G02X932427Y264505I-8J-2175D01*
G01X930890Y263992D02*
G02X931613Y263691I-2J-1024D01*
G01X930892Y265142D02*
G02X930897I2J-2175D01*
G01X930890Y263992D02*
G02X931613Y263691I-2J-1024D01*
G01X922800Y265142D02*
X930892D01*
G01X923184Y263992D02*
X930890D01*
G01X920111Y261683D02*
X923184Y263992D01*
G01X931613Y263691D02*
X933795Y261509D01*
G01X932427Y264505D02*
X934842Y262089D01*
G01X930890Y263992D02*
G02X931613Y263691I-2J-1024D01*
G01X930897Y265142D02*
G02X932427Y264505I-8J-2175D01*
G01X930892Y265142D02*
G02X930897I2J-2175D01*
G01X923184Y263992D02*
X930890D01*
G01X922800Y265142D02*
X930892D01*
G01X920111Y261683D02*
X923184Y263992D01*
G01X956169Y345695D02*
X911268Y381803D01*
G01X955312Y344907D02*
X910411Y381015D01*
G01X955312Y344907D02*
X910411Y381015D01*
G01X956169Y345695D02*
X911268Y381803D01*
G01X934379Y322076D02*
X934380D01*
G01X933795Y323119D02*
X933157Y322481D01*
G01X934842Y322539D02*
X934379Y322076D01*
G01X933795Y323119D02*
X933157Y322481D01*
G01X935135Y324374D02*
Y323246D01*
G01X933985Y324042D02*
Y323578D01*
G01X932751Y327173D02*
X934842Y325081D01*
G01X931937Y326359D02*
X933795Y324501D01*
G01X930431Y328134D02*
G02X932751Y327173I0J-3281D01*
G01X930430Y326984D02*
G02X931937Y326359I0J-2130D01*
G01X925659Y328134D02*
X930431D01*
G01X925608Y326984D02*
X930430D01*
G01X904460Y328857D02*
X925608Y326984D01*
G01X899679Y329281D02*
X901621Y329109D01*
G01X894898Y329705D02*
X896840Y329533D01*
G01X933795Y323119D02*
X933157Y322481D01*
G01X934379Y322076D02*
X934380D01*
G01X934842Y322539D02*
X934379Y322076D01*
G01X933985Y324042D02*
Y323578D01*
G01X935135Y324374D02*
Y323246D01*
G01X931937Y326359D02*
X933795Y324501D01*
G01X932751Y327173D02*
X934842Y325081D01*
G01X930430Y326984D02*
G02X931937Y326359I0J-2130D01*
G01X930431Y328134D02*
G02X932751Y327173I0J-3281D01*
G01X925608Y326984D02*
X930430D01*
G01X925659Y328134D02*
X930431D01*
G01X904460Y328857D02*
X925608Y326984D01*
G01X899679Y329281D02*
X901621Y329109D01*
G01X894898Y329705D02*
X896840Y329533D01*
G01X930431Y312386D02*
G02X932751Y311425I0J-3281D01*
G01X930430Y311236D02*
G02X931937Y310611I0J-2130D01*
G01X927508Y312386D02*
X930431D01*
G01X927431Y311236D02*
X930430D01*
G01X925498Y311495D02*
X927431Y311236D01*
G01X920741Y312132D02*
X922674Y311873D01*
G01X915983Y312770D02*
X917916Y312511D01*
G01X911226Y313407D02*
X913159Y313148D01*
G01X930430Y311236D02*
G02X931937Y310611I0J-2130D01*
G01X930431Y312386D02*
G02X932751Y311425I0J-3281D01*
G01X927431Y311236D02*
X930430D01*
G01X927508Y312386D02*
X930431D01*
G01X925498Y311495D02*
X927431Y311236D01*
G01X920741Y312132D02*
X922674Y311873D01*
G01X915983Y312770D02*
X917916Y312511D01*
G01X911226Y313407D02*
X913159Y313148D01*
G01X920997Y389900D02*
X911461Y404046D01*
G01X920141Y389112D02*
X910376Y403597D01*
G01X965617Y354147D02*
X920997Y389900D01*
G01X964761Y353359D02*
X920141Y389112D01*
G01D02*
X910376Y403597D01*
G01X920997Y389900D02*
X911461Y404046D01*
G01X964761Y353359D02*
X920141Y389112D01*
G01X965617Y354147D02*
X920997Y389900D01*
G01X926533Y393550D02*
X917980Y406228D01*
G01X925676Y392762D02*
X916895Y405778D01*
G01X970578Y358131D02*
X926533Y393550D01*
G01X969721Y357343D02*
X925676Y392762D01*
G01D02*
X916895Y405778D01*
G01X926533Y393550D02*
X917980Y406228D01*
G01X969721Y357343D02*
X925676Y392762D01*
G01X970578Y358131D02*
X926533Y393550D01*
G01X911268Y381803D02*
X898350Y400960D01*
G01X910411Y381015D02*
X897265Y400511D01*
G01X910411Y381015D02*
X897265Y400511D01*
G01X911268Y381803D02*
X898350Y400960D01*
G01X915974Y385981D02*
X905616Y401346D01*
G01X915117Y385193D02*
X904531Y400897D01*
G01X961169Y349635D02*
X915974Y385981D01*
G01X960312Y348847D02*
X915117Y385193D01*
G01D02*
X904531Y400897D01*
G01X915974Y385981D02*
X905616Y401346D01*
G01X960312Y348847D02*
X915117Y385193D01*
G01X961169Y349635D02*
X915974Y385981D01*
G01X897142Y607382D02*
X925539Y649485D01*
G01X920915Y644687D02*
X922005Y646304D01*
G01X918231Y640707D02*
X919321Y642324D01*
G01X915547Y636728D02*
X916637Y638345D01*
G01X896057Y607831D02*
X913953Y634365D01*
G01X897142Y607382D02*
X925539Y649485D01*
G01X920915Y644687D02*
X922005Y646304D01*
G01X897142Y607382D02*
X925539Y649485D01*
G01X918231Y640707D02*
X919321Y642324D01*
G01X897142Y607382D02*
X925539Y649485D01*
G01X915547Y636728D02*
X916637Y638345D01*
G01X897142Y607382D02*
X925539Y649485D01*
G01X896057Y607831D02*
X913953Y634365D01*
G01X897142Y607382D02*
X925539Y649485D01*
G01X932572Y667656D02*
X933379Y668463D01*
G01X931758Y668470D02*
X932156Y668868D01*
G01X931962Y667198D02*
G03X932572Y667656I-1301J2367D01*
G01X931408Y668207D02*
G03X931758Y668470I-747J1358D01*
G01X930663Y668015D02*
G03X931408Y668207I-2J1551D01*
G01X930662Y666865D02*
G03X931962Y667198I1J2701D01*
G01X931408Y668207D02*
G03X931758Y668470I-747J1358D01*
G01X930663Y668015D02*
G03X931408Y668207I-2J1551D01*
G01X927643Y666854D02*
X930662Y666865D01*
G01X927251Y668004D02*
X930663Y668015D01*
G01X924588Y664500D02*
X927643Y666854D01*
G01X923738Y665298D02*
X927251Y668004D01*
G01X923634Y665144D02*
X923738Y665298D01*
G01X921869Y662527D02*
X923634Y665144D01*
G01X919185Y658548D02*
X920276Y660164D01*
G01X916501Y654568D02*
X917592Y656185D01*
G01X913817Y650589D02*
X914908Y652205D01*
G01X931758Y668470D02*
X932156Y668868D01*
G01X932572Y667656D02*
X933379Y668463D01*
G01X931408Y668207D02*
G03X931758Y668470I-747J1358D01*
G01X931962Y667198D02*
G03X932572Y667656I-1301J2367D01*
G01X930662Y666865D02*
G03X931962Y667198I1J2701D01*
G01X930663Y668015D02*
G03X931408Y668207I-2J1551D01*
G01X931962Y667198D02*
G03X932572Y667656I-1301J2367D01*
G01X930662Y666865D02*
G03X931962Y667198I1J2701D01*
G01X927251Y668004D02*
X930663Y668015D01*
G01X927643Y666854D02*
X930662Y666865D01*
G01X923738Y665298D02*
X927251Y668004D01*
G01X924588Y664500D02*
X927643Y666854D01*
G01X923634Y665144D02*
X923738Y665298D01*
G01X921869Y662527D02*
X923634Y665144D01*
G01X919185Y658548D02*
X920276Y660164D01*
G01X916501Y654568D02*
X917592Y656185D01*
G01X913817Y650589D02*
X914908Y652205D01*
G01X932572Y651908D02*
X933379Y652715D01*
G01X931758Y652722D02*
X932156Y653120D01*
G01X931962Y651450D02*
G03X932572Y651908I-1301J2367D01*
G01X931408Y652459D02*
G03X931758Y652722I-747J1358D01*
G01X930663Y652267D02*
G03X931408Y652459I-2J1551D01*
G01X930662Y651117D02*
G03X931962Y651450I1J2701D01*
G01X931408Y652459D02*
G03X931758Y652722I-747J1358D01*
G01X930663Y652267D02*
G03X931408Y652459I-2J1551D01*
G01X929830Y651117D02*
X930662D01*
G01X929404Y652267D02*
X930663D01*
G01X927643Y651106D02*
X929830Y651117D01*
G01X929404Y652267D02*
X930663D01*
G01X927251Y652256D02*
X929404Y652267D01*
G01X925539Y649485D02*
X927643Y651106D01*
G01X924689Y650283D02*
X927251Y652256D01*
G01X923599Y648666D02*
X924689Y650283D01*
G01X931758Y652722D02*
X932156Y653120D01*
G01X932572Y651908D02*
X933379Y652715D01*
G01X931408Y652459D02*
G03X931758Y652722I-747J1358D01*
G01X931962Y651450D02*
G03X932572Y651908I-1301J2367D01*
G01X930662Y651117D02*
G03X931962Y651450I1J2701D01*
G01X930663Y652267D02*
G03X931408Y652459I-2J1551D01*
G01X931962Y651450D02*
G03X932572Y651908I-1301J2367D01*
G01X930662Y651117D02*
G03X931962Y651450I1J2701D01*
G01X929404Y652267D02*
X930663D01*
G01X929830Y651117D02*
X930662D01*
G01X927643Y651106D02*
X929830Y651117D01*
G01X927251Y652256D02*
X929404Y652267D01*
G01X927643Y651106D02*
X929830Y651117D01*
G01X924689Y650283D02*
X927251Y652256D01*
G01X925539Y649485D02*
X927643Y651106D01*
G01X923599Y648666D02*
X924689Y650283D01*
G01X924808Y696166D02*
X927643Y698350D01*
G01X921385Y693148D02*
X923958Y696964D01*
G01X918701Y689169D02*
X919791Y690785D01*
G01X916017Y685189D02*
X917107Y686806D01*
G01X913333Y681210D02*
X914423Y682826D01*
G01X924808Y696166D02*
X927643Y698350D01*
G01X921385Y693148D02*
X923958Y696964D01*
G01X918701Y689169D02*
X919791Y690785D01*
G01X916017Y685189D02*
X917107Y686806D01*
G01X913333Y681210D02*
X914423Y682826D01*
G01X932572Y683404D02*
X933379Y684211D01*
G01X931758Y684218D02*
X932156Y684616D01*
G01X931962Y682946D02*
G03X932572Y683404I-1301J2367D01*
G01X931408Y683955D02*
G03X931758Y684218I-747J1358D01*
G01X930663Y683763D02*
G03X931408Y683955I-2J1551D01*
G01X930662Y682613D02*
G03X931962Y682946I1J2701D01*
G01X931408Y683955D02*
G03X931758Y684218I-747J1358D01*
G01X930663Y683763D02*
G03X931408Y683955I-2J1551D01*
G01X927643Y682602D02*
X930662Y682613D01*
G01X927251Y683752D02*
X930663Y683763D01*
G01X925409Y680881D02*
X927643Y682602D01*
G01X924559Y681679D02*
X927251Y683752D01*
G01X921961Y677828D02*
X924559Y681679D01*
G01X919277Y673848D02*
X920368Y675465D01*
G01X916593Y669869D02*
X917684Y671485D01*
G01X913909Y665889D02*
X915000Y667506D01*
G01X931758Y684218D02*
X932156Y684616D01*
G01X932572Y683404D02*
X933379Y684211D01*
G01X931408Y683955D02*
G03X931758Y684218I-747J1358D01*
G01X931962Y682946D02*
G03X932572Y683404I-1301J2367D01*
G01X930662Y682613D02*
G03X931962Y682946I1J2701D01*
G01X930663Y683763D02*
G03X931408Y683955I-2J1551D01*
G01X931962Y682946D02*
G03X932572Y683404I-1301J2367D01*
G01X930662Y682613D02*
G03X931962Y682946I1J2701D01*
G01X927251Y683752D02*
X930663Y683763D01*
G01X927643Y682602D02*
X930662Y682613D01*
G01X924559Y681679D02*
X927251Y683752D01*
G01X925409Y680881D02*
X927643Y682602D01*
G01X921961Y677828D02*
X924559Y681679D01*
G01X919277Y673848D02*
X920368Y675465D01*
G01X916593Y669869D02*
X917684Y671485D01*
G01X913909Y665889D02*
X915000Y667506D01*
G01X932572Y699152D02*
X933379Y699959D01*
G01X931758Y699966D02*
X932156Y700364D01*
G01X931962Y698694D02*
G03X932572Y699152I-1301J2367D01*
G01X931408Y699703D02*
G03X931758Y699966I-747J1358D01*
G01X930663Y699511D02*
G03X931408Y699703I-2J1551D01*
G01X930662Y698361D02*
G03X931962Y698694I1J2701D01*
G01X931408Y699703D02*
G03X931758Y699966I-747J1358D01*
G01X930663Y699511D02*
G03X931408Y699703I-2J1551D01*
G01X927643Y698350D02*
X930662Y698361D01*
G01X930658Y699511D02*
X930663D01*
G01X927251Y699500D02*
X930658Y699511D01*
G01X923958Y696964D02*
X927251Y699500D01*
G01X931758Y699966D02*
X932156Y700364D01*
G01X932572Y699152D02*
X933379Y699959D01*
G01X931408Y699703D02*
G03X931758Y699966I-747J1358D01*
G01X931962Y698694D02*
G03X932572Y699152I-1301J2367D01*
G01X930662Y698361D02*
G03X931962Y698694I1J2701D01*
G01X930663Y699511D02*
G03X931408Y699703I-2J1551D01*
G01X931962Y698694D02*
G03X932572Y699152I-1301J2367D01*
G01X930662Y698361D02*
G03X931962Y698694I1J2701D01*
G01X930658Y699511D02*
X930663D01*
G01X927643Y698350D02*
X930662Y698361D01*
G01X927251Y699500D02*
X930658Y699511D01*
G01X927643Y698350D02*
X930662Y698361D01*
G01X923958Y696964D02*
X927251Y699500D01*
G01X915837Y975983D02*
X1027786Y607009D01*
G01X915837Y975983D02*
X1027786Y607009D01*
G01X929922Y1022174D02*
X1029815Y692930D01*
G01X931023Y1022507D02*
X1030869Y693420D01*
G01X931023Y1022507D02*
X1030869Y693420D01*
G01X929922Y1022174D02*
X1029815Y692930D01*
G01X924209Y1019266D02*
X1024814Y687301D01*
G01X924209Y1019266D02*
X1024814Y687301D01*
G01X956695Y114386D02*
X967314Y121038D01*
G01X956364Y115536D02*
X966496Y121884D01*
G01X952855Y114386D02*
X956695D01*
G01X952378Y115536D02*
X956364D01*
G01X949463Y110994D02*
X952855Y114386D01*
G01X948441Y111599D02*
X952378Y115536D01*
G01X948917Y110449D02*
X949463Y110994D01*
G01X948441Y111599D02*
X952378Y115536D01*
G01X956364D02*
X966496Y121884D01*
G01X956695Y114386D02*
X967314Y121038D01*
G01X952378Y115536D02*
X956364D01*
G01X952855Y114386D02*
X956695D01*
G01X948441Y111599D02*
X952378Y115536D01*
G01X949463Y110994D02*
X952855Y114386D01*
G01X948917Y110449D02*
X949463Y110994D01*
G01X956404Y106512D02*
X973162Y117006D01*
G01X956073Y107662D02*
X972344Y117852D01*
G01X952855Y106512D02*
X956404D01*
G01X952378Y107662D02*
X956073D01*
G01X948918Y102575D02*
X952855Y106512D01*
G01X948441Y103725D02*
X952378Y107662D01*
G01X956073D02*
X972344Y117852D01*
G01X956404Y106512D02*
X973162Y117006D01*
G01X952378Y107662D02*
X956073D01*
G01X952855Y106512D02*
X956404D01*
G01X948441Y103725D02*
X952378Y107662D01*
G01X948918Y102575D02*
X952855Y106512D01*
G01X974042Y131012D02*
X994657Y237057D01*
G01X972957Y131462D02*
X993485Y237057D01*
G01X967314Y121038D02*
X974042Y131012D01*
G01X966496Y121884D02*
X972957Y131462D01*
G01D02*
X993485Y237057D01*
G01X974042Y131012D02*
X994657Y237057D01*
G01X966496Y121884D02*
X972957Y131462D01*
G01X967314Y121038D02*
X974042Y131012D01*
G01X979787Y126829D02*
X1001231Y237117D01*
G01X978702Y127279D02*
X1000059Y237117D01*
G01X973162Y117006D02*
X979787Y126830D01*
G01X972344Y117852D02*
X978702Y127279D01*
G01D02*
X1000059Y237117D01*
G01X979787Y126829D02*
X1001231Y237117D01*
G01X972344Y117852D02*
X978702Y127279D01*
G01X973162Y117006D02*
X979787Y126830D01*
G01X962451Y137275D02*
X980849Y231927D01*
G01X961366Y137725D02*
X979677Y231927D01*
G01X957634Y130134D02*
X962451Y137275D01*
G01X957022Y131284D02*
X961366Y137724D01*
G01X952855Y130134D02*
X957634D01*
G01X952378Y131284D02*
X957022D01*
G01X948918Y126197D02*
X952855Y130134D01*
G01X948441Y127347D02*
X952378Y131284D01*
G01X961366Y137725D02*
X979677Y231927D01*
G01X962451Y137275D02*
X980849Y231927D01*
G01X957022Y131284D02*
X961366Y137724D01*
G01X957634Y130134D02*
X962451Y137275D01*
G01X952378Y131284D02*
X957022D01*
G01X952855Y130134D02*
X957634D01*
G01X948441Y127347D02*
X952378Y131284D01*
G01X948918Y126197D02*
X952855Y130134D01*
G01X968293Y134417D02*
X988284Y237258D01*
G01X967208Y134867D02*
X987112Y237258D01*
G01X962506Y125838D02*
X968293Y134417D01*
G01X961688Y126684D02*
X967208Y134867D01*
G01X956791Y122260D02*
X962506Y125838D01*
G01X959075Y125047D02*
X961688Y126684D01*
G01X956460Y123410D02*
X959075Y125047D01*
G01X952854Y122260D02*
X956791D01*
G01X952377Y123410D02*
X956460D01*
G01X948917Y118323D02*
X952854Y122260D01*
G01X948440Y119473D02*
X952377Y123410D01*
G01X967208Y134867D02*
X987112Y237258D01*
G01X968293Y134417D02*
X988284Y237258D01*
G01X961688Y126684D02*
X967208Y134867D01*
G01X962506Y125838D02*
X968293Y134417D01*
G01X959075Y125047D02*
X961688Y126684D01*
G01X956791Y122260D02*
X962506Y125838D01*
G01X956460Y123410D02*
X959075Y125047D01*
G01X956791Y122260D02*
X962506Y125838D01*
G01X952377Y123410D02*
X956460D01*
G01X952854Y122260D02*
X956791D01*
G01X948440Y119473D02*
X952377Y123410D01*
G01X948917Y118323D02*
X952854Y122260D01*
G01X994657Y237057D02*
X974439Y341068D01*
G01X993485Y237057D02*
X973354Y340619D01*
G01X993485Y237057D02*
X973354Y340619D01*
G01X994657Y237057D02*
X974439Y341068D01*
G01X980849Y231927D02*
X959794Y340321D01*
G01X979677Y231927D02*
X958709Y339872D01*
G01X979677Y231927D02*
X958709Y339872D01*
G01X980849Y231927D02*
X959794Y340321D01*
G01X988284Y237258D02*
X968574Y338654D01*
G01X987112Y237258D02*
X967489Y338205D01*
G01X987112Y237258D02*
X967489Y338205D01*
G01X988284Y237258D02*
X968574Y338654D01*
G01X1001231Y237117D02*
X980598Y343272D01*
G01X1000059Y237117D02*
X979513Y342823D01*
G01X1000059Y237117D02*
X979513Y342823D01*
G01X1001231Y237117D02*
X980598Y343272D01*
G01X974439Y341068D02*
X965617Y354147D01*
G01X973354Y340619D02*
X964761Y353359D01*
G01X973354Y340619D02*
X964761Y353359D01*
G01X974439Y341068D02*
X965617Y354147D01*
G01X980598Y343272D02*
X970578Y358131D01*
G01X979513Y342823D02*
X969721Y357343D01*
G01X979513Y342823D02*
X969721Y357343D01*
G01X980598Y343272D02*
X970578Y358131D01*
G01X959794Y340321D02*
X956169Y345695D01*
G01X958709Y339872D02*
X955312Y344907D01*
G01X958709Y339872D02*
X955312Y344907D01*
G01X959794Y340321D02*
X956169Y345695D01*
G01X968574Y338654D02*
X961169Y349635D01*
G01X967489Y338205D02*
X960312Y348847D01*
G01X967489Y338205D02*
X960312Y348847D01*
G01X968574Y338654D02*
X961169Y349635D01*
G01X1037160Y548885D02*
X1091804Y464741D01*
G01X1038214Y549375D02*
X1041636Y544105D01*
G01X1037649Y551238D02*
X1038214Y549375D01*
G01X1037160Y548885D02*
X1091804Y464741D01*
G01X1037160Y548885D02*
X1091804Y464741D01*
G01X1037160Y548885D02*
X1091804Y464741D01*
G01X1037160Y548885D02*
X1091804Y464741D01*
G01X1037160Y548885D02*
X1091804Y464741D01*
G01X1037160Y548885D02*
X1091804Y464741D01*
G01X1037160Y548885D02*
X1091804Y464741D01*
G01X1037160Y548885D02*
X1091804Y464741D01*
G01X1037160Y548885D02*
X1091804Y464741D01*
G01X1037160Y548885D02*
X1091804Y464741D01*
G01X1037160Y548885D02*
X1091804Y464741D01*
G01X1038214Y549375D02*
X1041636Y544105D01*
G01X1037160Y548885D02*
X1091804Y464741D01*
G01X1037649Y551238D02*
X1038214Y549375D01*
G01X1035760Y603454D02*
X1043787Y576998D01*
G01X1037690Y601059D02*
X1043496Y581924D01*
G01X1035760Y603454D02*
X1043787Y576998D01*
G01X1037690Y601059D02*
X1043496Y581924D01*
G01X1035760Y603454D02*
X1043787Y576998D01*
G01X1037500Y571027D02*
X1039720Y563710D01*
G01X1039428Y568636D02*
X1039993Y566776D01*
G01X1034713Y580214D02*
X1037499Y571030D01*
G01X1038035Y573229D02*
X1038601Y571363D01*
G01X1036641Y577822D02*
X1037207Y575956D01*
G01X1027513Y603946D02*
X1034712Y580217D01*
G01X1030007Y599688D02*
X1035814Y580550D01*
G01X1039428Y568636D02*
X1039993Y566776D01*
G01X1037500Y571027D02*
X1039720Y563710D01*
G01X1038035Y573229D02*
X1038601Y571363D01*
G01X1034713Y580214D02*
X1037499Y571030D01*
G01X1036641Y577822D02*
X1037207Y575956D01*
G01X1034713Y580214D02*
X1037499Y571030D01*
G01X1030007Y599688D02*
X1035814Y580550D01*
G01X1027513Y603946D02*
X1034712Y580217D01*
G01X1027513Y603946D02*
X1034712Y580217D01*
G01X1036254Y555834D02*
X1036820Y553968D01*
G01X1036254Y555834D02*
X1036820Y553968D01*
G01X1036295Y605656D02*
X1036861Y603790D01*
G01X1036295Y605656D02*
X1036861Y603790D01*
G01X1028613Y604281D02*
X1029180Y602415D01*
G01X1028613Y604281D02*
X1029180Y602415D01*
G01X1035356Y697573D02*
X1075403Y635906D01*
G01X1035356Y697573D02*
X1075403Y635906D01*
G01X1035356Y697573D02*
X1075403Y635906D01*
G01X1035356Y697573D02*
X1075403Y635906D01*
G01X1035356Y697573D02*
X1075403Y635906D01*
G01X1035356Y697573D02*
X1075403Y635906D01*
G01X1035356Y697573D02*
X1075403Y635906D01*
G01X1035356Y697573D02*
X1075403Y635906D01*
G01X1036410Y698063D02*
X1045523Y684030D01*
G01X1035356Y697573D02*
X1075403Y635906D01*
G01X1035356Y697573D02*
X1075403Y635906D01*
G01X1036410Y698063D02*
X1045523Y684030D01*
G01X1029815Y692930D02*
X1078890Y617356D01*
G01X1038120Y682255D02*
X1049012Y665481D01*
G01X1035505Y686281D02*
X1036567Y684645D01*
G01X1030869Y693420D02*
X1033953Y688671D01*
G01X1029815Y692930D02*
X1078890Y617356D01*
G01X1029815Y692930D02*
X1078890Y617356D01*
G01X1029815Y692930D02*
X1078890Y617356D01*
G01X1029815Y692930D02*
X1078890Y617356D01*
G01X1029815Y692930D02*
X1078890Y617356D01*
G01X1029815Y692930D02*
X1078890Y617356D01*
G01X1029815Y692930D02*
X1078890Y617356D01*
G01X1029815Y692930D02*
X1078890Y617356D01*
G01X1038120Y682255D02*
X1049012Y665481D01*
G01X1029815Y692930D02*
X1078890Y617356D01*
G01X1035505Y686281D02*
X1036567Y684645D01*
G01X1029815Y692930D02*
X1078890Y617356D01*
G01X1030869Y693420D02*
X1033953Y688671D01*
G01X1029815Y692930D02*
X1078890Y617356D01*
G01X1024814Y687301D02*
X1083133Y597492D01*
G01X1037134Y670442D02*
X1038196Y668807D01*
G01X1034520Y674468D02*
X1035582Y672833D01*
G01X1025868Y687791D02*
X1032968Y676858D01*
G01X1024814Y687301D02*
X1083133Y597492D01*
G01X1024814Y687301D02*
X1083133Y597492D01*
G01X1024814Y687301D02*
X1083133Y597492D01*
G01X1024814Y687301D02*
X1083133Y597492D01*
G01X1024814Y687301D02*
X1083133Y597492D01*
G01X1024814Y687301D02*
X1083133Y597492D01*
G01X1024814Y687301D02*
X1083133Y597492D01*
G01X1024814Y687301D02*
X1083133Y597492D01*
G01X1024814Y687301D02*
X1083133Y597492D01*
G01X1037134Y670442D02*
X1038196Y668807D01*
G01X1024814Y687301D02*
X1083133Y597492D01*
G01X1034520Y674468D02*
X1035582Y672833D01*
G01X1024814Y687301D02*
X1083133Y597492D01*
G01X1025868Y687791D02*
X1032968Y676858D01*
G01X1024814Y687301D02*
X1083133Y597492D01*
G01X1039322Y707412D02*
X1039934Y705395D01*
G01X1037100Y714735D02*
X1039321Y707415D01*
G01X1039028Y712344D02*
X1039594Y710478D01*
G01X1035706Y719329D02*
X1037099Y714738D01*
G01X1037636Y716934D02*
X1038201Y715071D01*
G01X1027678Y745788D02*
X1035705Y719332D01*
G01X1036241Y721531D02*
X1036807Y719665D01*
G01X1029607Y743396D02*
X1035414Y724258D01*
G01X1039322Y707412D02*
X1039934Y705395D01*
G01X1039028Y712344D02*
X1039594Y710478D01*
G01X1037100Y714735D02*
X1039321Y707415D01*
G01X1037636Y716934D02*
X1038201Y715071D01*
G01X1035706Y719329D02*
X1037099Y714738D01*
G01X1036241Y721531D02*
X1036807Y719665D01*
G01X1027678Y745788D02*
X1035705Y719332D01*
G01X1029607Y743396D02*
X1035414Y724258D01*
G01X1027678Y745788D02*
X1035705Y719332D01*
G01X1035846Y699923D02*
X1036410Y698063D01*
G01X1034744Y699590D02*
X1035356Y697573D01*
G01X1034450Y704522D02*
X1035016Y702656D01*
G01X1032522Y706913D02*
X1034743Y699593D01*
G01X1034744Y699590D02*
X1035356Y697573D01*
G01X1035846Y699923D02*
X1036410Y698063D01*
G01X1032522Y706913D02*
X1034743Y699593D01*
G01X1034450Y704522D02*
X1035016Y702656D01*
G01X1028213Y747990D02*
X1028779Y746124D01*
G01X1028213Y747990D02*
X1028779Y746124D01*
G01X1089282Y148947D02*
X1070258Y178813D01*
G01X1071337Y179260D02*
X1090115Y149781D01*
G01X1071337Y179260D02*
X1090115Y149781D01*
G01X1089282Y148947D02*
X1070258Y178813D01*
G01X1087053Y199727D02*
X1074357Y256981D01*
G01X1088132Y200174D02*
X1079217Y240387D01*
G01X1089856Y195329D02*
X1087053Y199727D01*
G01D02*
X1074357Y256981D01*
G01X1087053Y199727D02*
X1074357Y256981D01*
G01X1087053Y199727D02*
X1074357Y256981D01*
G01X1088132Y200174D02*
X1079217Y240387D01*
G01X1087053Y199727D02*
X1074357Y256981D01*
G01X1089856Y195329D02*
X1087053Y199727D01*
G01X1080863Y195252D02*
X1065993Y262341D01*
G01X1077660Y215020D02*
X1081942Y195699D01*
G01X1090518Y180108D02*
X1080863Y195252D01*
G01X1081942Y195699D02*
X1091351Y180941D01*
G01X1081942Y195699D02*
X1091351Y180941D01*
G01X1090518Y180108D02*
X1080863Y195252D01*
G01X1077660Y215020D02*
X1081942Y195699D01*
G01X1080863Y195252D02*
X1065993Y262341D01*
G01X1080863Y195252D02*
X1065993Y262341D01*
G01X1080863Y195252D02*
X1065993Y262341D01*
G01X1080863Y195252D02*
X1065993Y262341D01*
G01X1080863Y195252D02*
X1065993Y262341D01*
G01X1075782Y186629D02*
X1089770Y164646D01*
G01X1076861Y187076D02*
X1090604Y165480D01*
G01X1059186Y261469D02*
X1075782Y186629D01*
G01X1063941Y245342D02*
X1076861Y187076D01*
G01D02*
X1090604Y165480D01*
G01X1075782Y186629D02*
X1089770Y164646D01*
G01X1063941Y245342D02*
X1076861Y187076D01*
G01X1059186Y261469D02*
X1075782Y186629D01*
G01X1059186Y261469D02*
X1075782Y186629D01*
G01X1059186Y261469D02*
X1075782Y186629D01*
G01X1059186Y261469D02*
X1075782Y186629D01*
G01X1070258Y178813D02*
X1051641Y262778D01*
G01X1056395Y246652D02*
X1071337Y179260D01*
G01X1056395Y246652D02*
X1071337Y179260D01*
G01X1070258Y178813D02*
X1051641Y262778D01*
G01X1070258Y178813D02*
X1051641Y262778D01*
G01X1070258Y178813D02*
X1051641Y262778D01*
G01X1070258Y178813D02*
X1051641Y262778D01*
G01X1074051Y258359D02*
X1089856Y338662D01*
G01X1075227Y258374D02*
X1077068Y267729D01*
G01X1074359Y256982D02*
X1074051Y258359D01*
G01X1075482Y257232D02*
X1075227Y258374D01*
G01X1076522Y252542D02*
X1076101Y254441D01*
G01X1077561Y247856D02*
X1077139Y249760D01*
G01X1078600Y243170D02*
X1078178Y245073D01*
G01X1074051Y258359D02*
X1089856Y338662D01*
G01X1074051Y258359D02*
X1089856Y338662D01*
G01X1074051Y258359D02*
X1089856Y338662D01*
G01X1074051Y258359D02*
X1089856Y338662D01*
G01X1074051Y258359D02*
X1089856Y338662D01*
G01X1074051Y258359D02*
X1089856Y338662D01*
G01X1074051Y258359D02*
X1089856Y338662D01*
G01X1074051Y258359D02*
X1089856Y338662D01*
G01X1075227Y258374D02*
X1077068Y267729D01*
G01X1074051Y258359D02*
X1089856Y338662D01*
G01X1075482Y257232D02*
X1075227Y258374D01*
G01X1074359Y256982D02*
X1074051Y258359D01*
G01X1076522Y252542D02*
X1076101Y254441D01*
G01X1077561Y247856D02*
X1077139Y249760D01*
G01X1078600Y243170D02*
X1078178Y245073D01*
G01X1076621Y219706D02*
X1077043Y217802D01*
G01X1075582Y224392D02*
X1076004Y222488D01*
G01X1074544Y229079D02*
X1074966Y227175D01*
G01X1067171Y262341D02*
X1073927Y231861D01*
G01X1076621Y219706D02*
X1077043Y217802D01*
G01X1075582Y224392D02*
X1076004Y222488D01*
G01X1074544Y229079D02*
X1074966Y227175D01*
G01X1067171Y262341D02*
X1073927Y231861D01*
G01X1062902Y250028D02*
X1063324Y248124D01*
G01X1061863Y254714D02*
X1062285Y252810D01*
G01X1060824Y259400D02*
X1061246Y257497D01*
G01X1062902Y250028D02*
X1063324Y248124D01*
G01X1061863Y254714D02*
X1062285Y252810D01*
G01X1060824Y259400D02*
X1061246Y257497D01*
G01X1055356Y251338D02*
X1055778Y249434D01*
G01X1054317Y256024D02*
X1054739Y254120D01*
G01X1053278Y260710D02*
X1053700Y258807D01*
G01X1055356Y251338D02*
X1055778Y249434D01*
G01X1054317Y256024D02*
X1054739Y254120D01*
G01X1053278Y260710D02*
X1053700Y258807D01*
G01X1080461Y284969D02*
X1086494Y315619D01*
G01X1079519Y280181D02*
X1079895Y282094D01*
G01X1078576Y275392D02*
X1078953Y277306D01*
G01X1077634Y270604D02*
X1078011Y272518D01*
G01X1080461Y284969D02*
X1086494Y315619D01*
G01X1079519Y280181D02*
X1079895Y282094D01*
G01X1078576Y275392D02*
X1078953Y277306D01*
G01X1077634Y270604D02*
X1078011Y272518D01*
G01X1065993Y262341D02*
X1083244Y340109D01*
G01X1080096Y320605D02*
X1067171Y262341D01*
G01X1080096Y320605D02*
X1067171Y262341D01*
G01X1065993D02*
X1083244Y340109D01*
G01X1065993Y262341D02*
X1083244Y340109D01*
G01X1065993Y262341D02*
X1083244Y340109D01*
G01X1065993Y262341D02*
X1083244Y340109D01*
G01X1065993Y262341D02*
X1083244Y340109D01*
G01X1058786Y263275D02*
X1059187Y261469D01*
G01X1059965Y263275D02*
X1060207Y262183D01*
G01X1076671Y343911D02*
X1058786Y263275D01*
G01X1073402Y323861D02*
X1059965Y263275D01*
G01D02*
X1060207Y262183D01*
G01X1058786Y263275D02*
X1059187Y261469D01*
G01X1073402Y323861D02*
X1059965Y263275D01*
G01X1076671Y343911D02*
X1058786Y263275D01*
G01X1076671Y343911D02*
X1058786Y263275D01*
G01X1076671Y343911D02*
X1058786Y263275D01*
G01X1076671Y343911D02*
X1058786Y263275D01*
G01X1076671Y343911D02*
X1058786Y263275D01*
G01X1050932Y265979D02*
X1067725Y342163D01*
G01X1064603Y322654D02*
X1052110Y265979D01*
G01X1051640Y262779D02*
X1050932Y265979D01*
G01X1052110D02*
X1052660Y263494D01*
G01X1052110Y265979D02*
X1052660Y263494D01*
G01X1051640Y262779D02*
X1050932Y265979D01*
G01X1064603Y322654D02*
X1052110Y265979D01*
G01X1050932D02*
X1067725Y342163D01*
G01X1050932Y265979D02*
X1067725Y342163D01*
G01X1050932Y265979D02*
X1067725Y342163D01*
G01X1050932Y265979D02*
X1067725Y342163D01*
G01X1050932Y265979D02*
X1067725Y342163D01*
G01X1087059Y318494D02*
X1087436Y320407D01*
G01X1087059Y318494D02*
X1087436Y320407D01*
G01X1083244Y340109D02*
X1091309Y352764D01*
G01X1092142Y351931D02*
X1084323Y339662D01*
G01X1081153Y325369D02*
X1080730Y323466D01*
G01X1082209Y330134D02*
X1081787Y328230D01*
G01X1083266Y334898D02*
X1082844Y332994D01*
G01X1084323Y339662D02*
X1083901Y337758D01*
G01X1081153Y325369D02*
X1080730Y323466D01*
G01X1082209Y330134D02*
X1081787Y328230D01*
G01X1083266Y334898D02*
X1082844Y332994D01*
G01X1084323Y339662D02*
X1083901Y337758D01*
G01X1092142Y351931D02*
X1084323Y339662D01*
G01X1083244Y340109D02*
X1091309Y352764D01*
G01X1074459Y328626D02*
X1074037Y326722D01*
G01X1075516Y333390D02*
X1075093Y331486D01*
G01X1076572Y338154D02*
X1076150Y336250D01*
G01X1077750Y343464D02*
X1077207Y341015D01*
G01X1084921Y356877D02*
X1076671Y343911D01*
G01X1085755Y356043D02*
X1077750Y343464D01*
G01X1099829Y366370D02*
X1084921Y356877D01*
G01X1100276Y365291D02*
X1085755Y356043D01*
G01X1074459Y328626D02*
X1074037Y326722D01*
G01X1075516Y333390D02*
X1075093Y331486D01*
G01X1076572Y338154D02*
X1076150Y336250D01*
G01X1077750Y343464D02*
X1077207Y341015D01*
G01X1085755Y356043D02*
X1077750Y343464D01*
G01X1084921Y356877D02*
X1076671Y343911D01*
G01X1100276Y365291D02*
X1085755Y356043D01*
G01X1099829Y366370D02*
X1084921Y356877D01*
G01X1067725Y342163D02*
X1080615Y362396D01*
G01X1081448Y361563D02*
X1068805Y341716D01*
G01X1065654Y327419D02*
X1065234Y325515D01*
G01X1066704Y332185D02*
X1066284Y330281D01*
G01X1067755Y336950D02*
X1067335Y335046D01*
G01X1068805Y341716D02*
X1068385Y339812D01*
G01X1065654Y327419D02*
X1065234Y325515D01*
G01X1066704Y332185D02*
X1066284Y330281D01*
G01X1067755Y336950D02*
X1067335Y335046D01*
G01X1068805Y341716D02*
X1068385Y339812D01*
G01X1081448Y361563D02*
X1068805Y341716D01*
G01X1067725Y342163D02*
X1080615Y362396D01*
G01X1080614D02*
X1095514Y371888D01*
G01X1095961Y370809D02*
X1081448Y361563D01*
G01X1095961Y370809D02*
X1081448Y361563D01*
G01X1080614Y362396D02*
X1095514Y371888D01*
G01X1048015Y563063D02*
X1089349Y498775D01*
G01X1048015Y563063D02*
X1089349Y498775D01*
G01X1048015Y563063D02*
X1089349Y498775D01*
G01X1048015Y563063D02*
X1089349Y498775D01*
G01X1048015Y563063D02*
X1089349Y498775D01*
G01X1048015Y563063D02*
X1089349Y498775D01*
G01X1048015Y563063D02*
X1089349Y498775D01*
G01X1048015Y563063D02*
X1089349Y498775D01*
G01X1048015Y563063D02*
X1089349Y498775D01*
G01X1042288Y555247D02*
X1089306Y482845D01*
G01X1086451Y489354D02*
X1090171Y483626D01*
G01X1083793Y493447D02*
X1084855Y491811D01*
G01X1081135Y497540D02*
X1082197Y495904D01*
G01X1068821Y516502D02*
X1079540Y499997D01*
G01X1086451Y489354D02*
X1090171Y483626D01*
G01X1042288Y555247D02*
X1089306Y482845D01*
G01X1083793Y493447D02*
X1084855Y491811D01*
G01X1042288Y555247D02*
X1089306Y482845D01*
G01X1081135Y497540D02*
X1082197Y495904D01*
G01X1042288Y555247D02*
X1089306Y482845D01*
G01X1068821Y516502D02*
X1079540Y499997D01*
G01X1042288Y555247D02*
X1089306Y482845D01*
G01X1042288Y555247D02*
X1089306Y482845D01*
G01X1042288Y555247D02*
X1089306Y482845D01*
G01X1042288Y555247D02*
X1089306Y482845D01*
G01X1042288Y555247D02*
X1089306Y482845D01*
G01X1086291Y475343D02*
X1087353Y473707D01*
G01X1083633Y479436D02*
X1084695Y477800D01*
G01X1071319Y498398D02*
X1082038Y481893D01*
G01X1068705Y502424D02*
X1069767Y500788D01*
G01X1086291Y475343D02*
X1087353Y473707D01*
G01X1083633Y479436D02*
X1084695Y477800D01*
G01X1071319Y498398D02*
X1082038Y481893D01*
G01X1068705Y502424D02*
X1069767Y500788D01*
G01X1053758Y568202D02*
X1089343Y513381D01*
G01X1085679Y521139D02*
X1090208Y514162D01*
G01X1083022Y525232D02*
X1084084Y523597D01*
G01X1080365Y529326D02*
X1081427Y527690D01*
G01X1068865Y547042D02*
X1078770Y531783D01*
G01X1066252Y551069D02*
X1067313Y549433D01*
G01X1085679Y521139D02*
X1090208Y514162D01*
G01X1053758Y568202D02*
X1089343Y513381D01*
G01X1083022Y525232D02*
X1084084Y523597D01*
G01X1053758Y568202D02*
X1089343Y513381D01*
G01X1080365Y529326D02*
X1081427Y527690D01*
G01X1053758Y568202D02*
X1089343Y513381D01*
G01X1068865Y547042D02*
X1078770Y531783D01*
G01X1053758Y568202D02*
X1089343Y513381D01*
G01X1066252Y551069D02*
X1067313Y549433D01*
G01X1053758Y568202D02*
X1089343Y513381D01*
G01X1053758Y568202D02*
X1089343Y513381D01*
G01X1053758Y568202D02*
X1089343Y513381D01*
G01X1053758Y568202D02*
X1089343Y513381D01*
G01X1083740Y509628D02*
X1090216Y499555D01*
G01X1081101Y513733D02*
X1082155Y512092D01*
G01X1078461Y517837D02*
X1079516Y516197D01*
G01X1069016Y532528D02*
X1076877Y520302D01*
G01X1066420Y536565D02*
X1067475Y534925D01*
G01X1063824Y540603D02*
X1064879Y538963D01*
G01X1061228Y544640D02*
X1062283Y543000D01*
G01X1049070Y563551D02*
X1059687Y547038D01*
G01X1083740Y509628D02*
X1090216Y499555D01*
G01X1081101Y513733D02*
X1082155Y512092D01*
G01X1078461Y517837D02*
X1079516Y516197D01*
G01X1069016Y532528D02*
X1076877Y520302D01*
G01X1066420Y536565D02*
X1067475Y534925D01*
G01X1063824Y540603D02*
X1064879Y538963D01*
G01X1061228Y544640D02*
X1062283Y543000D01*
G01X1049070Y563551D02*
X1059687Y547038D01*
G01X1066207Y520528D02*
X1067269Y518892D01*
G01X1063593Y524553D02*
X1064655Y522918D01*
G01X1060978Y528579D02*
X1062040Y526943D01*
G01X1043342Y555737D02*
X1059426Y530969D01*
G01X1066207Y520528D02*
X1067269Y518892D01*
G01X1063593Y524553D02*
X1064655Y522918D01*
G01X1060978Y528579D02*
X1062040Y526943D01*
G01X1043342Y555737D02*
X1059426Y530969D01*
G01X1066091Y506449D02*
X1067153Y504814D01*
G01X1063476Y510475D02*
X1064538Y508839D01*
G01X1051031Y529638D02*
X1061924Y512865D01*
G01X1048417Y533664D02*
X1049479Y532029D01*
G01X1045803Y537690D02*
X1046865Y536054D01*
G01X1043189Y541715D02*
X1044251Y540080D01*
G01X1066091Y506449D02*
X1067153Y504814D01*
G01X1063476Y510475D02*
X1064538Y508839D01*
G01X1051031Y529638D02*
X1061924Y512865D01*
G01X1048417Y533664D02*
X1049479Y532029D01*
G01X1045803Y537690D02*
X1046865Y536054D01*
G01X1043189Y541715D02*
X1044251Y540080D01*
G01X1083133Y597492D02*
X1094925Y588008D01*
G01X1087738Y595265D02*
X1089258Y594043D01*
G01X1085518Y597051D02*
X1086150Y597120D01*
G01X1083998Y598273D02*
X1085518Y597051D01*
G01X1082671Y600317D02*
X1083998Y598273D01*
G01X1083133Y597492D02*
X1094925Y588008D01*
G01X1083133Y597492D02*
X1094925Y588008D01*
G01X1087738Y595265D02*
X1089258Y594043D01*
G01X1083133Y597492D02*
X1094925Y588008D01*
G01X1085518Y597051D02*
X1086150Y597120D01*
G01X1083133Y597492D02*
X1094925Y588008D01*
G01X1083998Y598273D02*
X1085518Y597051D01*
G01X1083133Y597492D02*
X1094925Y588008D01*
G01X1082671Y600317D02*
X1083998Y598273D01*
G01X1063638Y555095D02*
X1064700Y553459D01*
G01X1061025Y559121D02*
X1062086Y557485D01*
G01X1054812Y568692D02*
X1059473Y561511D01*
G01X1053146Y570219D02*
X1053758Y568202D01*
G01X1054248Y570552D02*
X1054812Y568692D01*
G01X1050924Y577542D02*
X1053145Y570222D01*
G01X1052852Y575151D02*
X1053418Y573285D01*
G01X1049530Y582136D02*
X1050923Y577545D01*
G01X1051460Y579741D02*
X1052025Y577878D01*
G01X1040108Y613191D02*
X1049529Y582139D01*
G01X1050065Y584338D02*
X1050631Y582472D01*
G01X1043431Y606203D02*
X1049238Y587065D01*
G01X1063638Y555095D02*
X1064700Y553459D01*
G01X1061025Y559121D02*
X1062086Y557485D01*
G01X1054812Y568692D02*
X1059473Y561511D01*
G01X1054248Y570552D02*
X1054812Y568692D01*
G01X1053146Y570219D02*
X1053758Y568202D01*
G01X1052852Y575151D02*
X1053418Y573285D01*
G01X1050924Y577542D02*
X1053145Y570222D01*
G01X1051460Y579741D02*
X1052025Y577878D01*
G01X1049530Y582136D02*
X1050923Y577545D01*
G01X1050065Y584338D02*
X1050631Y582472D01*
G01X1040108Y613191D02*
X1049529Y582139D01*
G01X1043431Y606203D02*
X1049238Y587065D01*
G01X1040108Y613191D02*
X1049529Y582139D01*
G01X1040108Y613191D02*
X1049529Y582139D01*
G01X1043788Y576995D02*
X1048015Y563063D01*
G01X1048504Y565417D02*
X1049070Y563551D01*
G01X1047111Y570007D02*
X1047676Y568144D01*
G01X1045717Y574603D02*
X1046283Y572737D01*
G01X1044323Y579197D02*
X1044889Y577331D01*
G01X1048504Y565417D02*
X1049070Y563551D01*
G01X1043788Y576995D02*
X1048015Y563063D01*
G01X1047111Y570007D02*
X1047676Y568144D01*
G01X1043788Y576995D02*
X1048015Y563063D01*
G01X1045717Y574603D02*
X1046283Y572737D01*
G01X1043788Y576995D02*
X1048015Y563063D01*
G01X1044323Y579197D02*
X1044889Y577331D01*
G01X1039721Y563707D02*
X1042288Y555247D01*
G01X1040823Y564040D02*
X1043342Y555737D01*
G01X1040823Y564040D02*
X1043342Y555737D01*
G01X1039721Y563707D02*
X1042288Y555247D01*
G01X1077275Y647891D02*
X1092991Y635252D01*
G01X1078140Y648672D02*
X1093397Y636402D01*
G01X1078140Y648672D02*
X1093397Y636402D01*
G01X1077275Y647891D02*
X1092991Y635252D01*
G01X1087677Y627513D02*
X1096206Y620654D01*
G01X1075403Y635906D02*
X1095800Y619504D01*
G01X1085394Y629349D02*
X1086082Y629424D01*
G01X1075403Y635906D02*
X1095800Y619504D01*
G01X1083874Y630571D02*
X1085394Y629349D01*
G01X1075403Y635906D02*
X1095800Y619504D01*
G01X1081591Y632407D02*
X1082279Y632482D01*
G01X1075403Y635906D02*
X1095800Y619504D01*
G01X1080071Y633629D02*
X1081591Y632407D01*
G01X1075403Y635906D02*
X1095800Y619504D01*
G01X1077788Y635465D02*
X1078477Y635540D01*
G01X1075403Y635906D02*
X1095800Y619504D01*
G01X1076268Y636687D02*
X1077788Y635465D01*
G01X1075403Y635906D02*
X1095800Y619504D01*
G01X1075206Y638322D02*
X1076268Y636687D01*
G01X1072592Y642348D02*
X1073654Y640713D01*
G01X1069977Y646374D02*
X1071039Y644738D01*
G01X1075403Y635906D02*
X1095800Y619504D01*
G01X1087677Y627513D02*
X1096206Y620654D01*
G01X1085394Y629349D02*
X1086082Y629424D01*
G01X1083874Y630571D02*
X1085394Y629349D01*
G01X1081591Y632407D02*
X1082279Y632482D01*
G01X1080071Y633629D02*
X1081591Y632407D01*
G01X1077788Y635465D02*
X1078477Y635540D01*
G01X1076268Y636687D02*
X1077788Y635465D01*
G01X1075206Y638322D02*
X1076268Y636687D01*
G01X1072592Y642348D02*
X1073654Y640713D01*
G01X1069977Y646374D02*
X1071039Y644738D01*
G01X1078890Y617356D02*
X1095800Y603756D01*
G01X1087360Y612020D02*
X1088880Y610798D01*
G01X1085077Y613856D02*
X1085766Y613931D01*
G01X1083558Y615079D02*
X1085077Y613856D01*
G01X1081275Y616915D02*
X1081963Y616990D01*
G01X1079755Y618137D02*
X1081275Y616915D01*
G01X1078693Y619772D02*
X1079755Y618137D01*
G01X1076079Y623798D02*
X1077141Y622163D01*
G01X1073465Y627824D02*
X1074527Y626188D01*
G01X1070851Y631850D02*
X1071913Y630214D01*
G01X1058406Y651014D02*
X1069298Y634240D01*
G01X1078890Y617356D02*
X1095800Y603756D01*
G01X1078890Y617356D02*
X1095800Y603756D01*
G01X1087360Y612020D02*
X1088880Y610798D01*
G01X1078890Y617356D02*
X1095800Y603756D01*
G01X1085077Y613856D02*
X1085766Y613931D01*
G01X1078890Y617356D02*
X1095800Y603756D01*
G01X1083558Y615079D02*
X1085077Y613856D01*
G01X1078890Y617356D02*
X1095800Y603756D01*
G01X1081275Y616915D02*
X1081963Y616990D01*
G01X1078890Y617356D02*
X1095800Y603756D01*
G01X1079755Y618137D02*
X1081275Y616915D01*
G01X1078890Y617356D02*
X1095800Y603756D01*
G01X1078693Y619772D02*
X1079755Y618137D01*
G01X1076079Y623798D02*
X1077141Y622163D01*
G01X1073465Y627824D02*
X1074527Y626188D01*
G01X1070851Y631850D02*
X1071913Y630214D01*
G01X1058406Y651014D02*
X1069298Y634240D01*
G01X1080013Y604409D02*
X1081075Y602774D01*
G01X1077356Y608502D02*
X1078418Y606867D01*
G01X1062649Y631150D02*
X1075760Y610959D01*
G01X1060035Y635175D02*
X1061097Y633540D01*
G01X1057421Y639201D02*
X1058483Y637566D01*
G01X1054807Y643227D02*
X1055869Y641591D01*
G01X1042363Y662391D02*
X1053255Y645617D01*
G01X1080013Y604409D02*
X1081075Y602774D01*
G01X1077356Y608502D02*
X1078418Y606867D01*
G01X1062649Y631150D02*
X1075760Y610959D01*
G01X1060035Y635175D02*
X1061097Y633540D01*
G01X1057421Y639201D02*
X1058483Y637566D01*
G01X1054807Y643227D02*
X1055869Y641591D01*
G01X1042363Y662391D02*
X1053255Y645617D01*
G01X1042037Y610797D02*
X1042603Y608931D01*
G01X1042037Y610797D02*
X1042603Y608931D01*
G01X1079109Y714730D02*
X1091576Y685077D01*
G01X1072126Y713515D02*
X1090433Y669967D01*
G01X1073338Y713600D02*
X1091340Y670778D01*
G01X1073338Y713600D02*
X1091340Y670778D01*
G01X1072126Y713515D02*
X1090433Y669967D01*
G01X1065036Y711868D02*
X1089244Y654279D01*
G01X1066248Y711953D02*
X1090151Y655090D01*
G01X1066248Y711953D02*
X1090151Y655090D01*
G01X1065036Y711868D02*
X1089244Y654279D01*
G01X1079109Y714730D02*
X1091576Y685077D01*
G01X1039934Y705395D02*
X1077275Y647891D01*
G01X1075256Y653113D02*
X1078140Y648672D01*
G01X1072599Y657206D02*
X1073661Y655570D01*
G01X1069941Y661298D02*
X1071003Y659663D01*
G01X1056791Y681549D02*
X1068345Y663756D01*
G01X1054177Y685574D02*
X1055239Y683939D01*
G01X1051563Y689600D02*
X1052625Y687965D01*
G01X1048949Y693626D02*
X1050011Y691990D01*
G01X1040988Y705885D02*
X1047397Y696016D01*
G01X1075256Y653113D02*
X1078140Y648672D01*
G01X1039934Y705395D02*
X1077275Y647891D01*
G01X1072599Y657206D02*
X1073661Y655570D01*
G01X1039934Y705395D02*
X1077275Y647891D01*
G01X1069941Y661298D02*
X1071003Y659663D01*
G01X1039934Y705395D02*
X1077275Y647891D01*
G01X1056791Y681549D02*
X1068345Y663756D01*
G01X1039934Y705395D02*
X1077275Y647891D01*
G01X1054177Y685574D02*
X1055239Y683939D01*
G01X1039934Y705395D02*
X1077275Y647891D01*
G01X1051563Y689600D02*
X1052625Y687965D01*
G01X1039934Y705395D02*
X1077275Y647891D01*
G01X1048949Y693626D02*
X1050011Y691990D01*
G01X1039934Y705395D02*
X1077275Y647891D01*
G01X1040988Y705885D02*
X1047397Y696016D01*
G01X1039934Y705395D02*
X1077275Y647891D01*
G01X1067363Y650399D02*
X1068425Y648764D01*
G01X1054918Y669563D02*
X1065811Y652789D01*
G01X1052304Y673589D02*
X1053366Y671953D01*
G01X1049690Y677614D02*
X1050752Y675979D01*
G01X1047075Y681640D02*
X1048137Y680004D01*
G01X1067363Y650399D02*
X1068425Y648764D01*
G01X1054918Y669563D02*
X1065811Y652789D01*
G01X1052304Y673589D02*
X1053366Y671953D01*
G01X1049690Y677614D02*
X1050752Y675979D01*
G01X1047075Y681640D02*
X1048137Y680004D01*
G01X1055792Y655039D02*
X1056854Y653404D01*
G01X1053178Y659065D02*
X1054240Y657430D01*
G01X1050564Y663091D02*
X1051626Y661455D01*
G01X1055792Y655039D02*
X1056854Y653404D01*
G01X1053178Y659065D02*
X1054240Y657430D01*
G01X1050564Y663091D02*
X1051626Y661455D01*
G01X1039748Y666417D02*
X1040810Y664781D01*
G01X1039748Y666417D02*
X1040810Y664781D01*
G01X1087721Y715199D02*
X1093713Y700949D01*
G01X1086509Y715114D02*
X1092805Y700138D01*
G01X1090493Y725703D02*
X1087721Y715199D01*
G01X1089476Y726362D02*
X1086509Y715114D01*
G01D02*
X1092805Y700138D01*
G01X1087721Y715199D02*
X1093713Y700949D01*
G01X1089476Y726362D02*
X1086509Y715114D01*
G01X1090493Y725703D02*
X1087721Y715199D01*
G01X1080321Y714815D02*
X1092483Y685888D01*
G01X1084008Y728794D02*
X1080321Y714815D01*
G01X1082992Y729454D02*
X1079109Y714730D01*
G01X1098018Y740062D02*
X1084008Y728794D01*
G01X1097464Y741093D02*
X1082992Y729454D01*
G01X1077215Y732807D02*
X1072126Y713515D01*
G01X1078231Y732147D02*
X1073338Y713600D01*
G01X1094655Y746837D02*
X1077215Y732807D01*
G01X1095209Y745806D02*
X1078231Y732148D01*
G01Y732147D02*
X1073338Y713600D01*
G01X1077215Y732807D02*
X1072126Y713515D01*
G01X1095209Y745806D02*
X1078231Y732148D01*
G01X1094655Y746837D02*
X1077215Y732807D01*
G01X1071456Y736203D02*
X1065036Y711868D01*
G01X1072472Y735543D02*
X1066248Y711953D01*
G01X1092908Y753461D02*
X1071456Y736203D01*
G01X1093462Y752430D02*
X1072472Y735544D01*
G01Y735543D02*
X1066248Y711953D01*
G01X1071456Y736203D02*
X1065036Y711868D01*
G01X1093462Y752430D02*
X1072472Y735544D01*
G01X1092908Y753461D02*
X1071456Y736203D01*
G01X1080321Y714815D02*
X1092483Y685888D01*
G01X1082992Y729454D02*
X1079109Y714730D01*
G01X1084008Y728794D02*
X1080321Y714815D01*
G01X1097464Y741093D02*
X1082992Y729454D01*
G01X1098018Y740062D02*
X1084008Y728794D01*
G01X1040424Y707745D02*
X1040988Y705885D01*
G01X1040424Y707745D02*
X1040988Y705885D01*
G01X1100682Y162539D02*
X1101489Y163346D01*
G01X1099868Y163353D02*
X1100266Y163751D01*
G01X1100072Y162081D02*
G03X1100682Y162539I-1301J2367D01*
G01X1099518Y163090D02*
G03X1099868Y163353I-747J1358D01*
G01X1098773Y162898D02*
G03X1099518Y163090I-2J1551D01*
G01X1098772Y161748D02*
G03X1100072Y162081I1J2701D01*
G01X1099518Y163090D02*
G03X1099868Y163353I-747J1358D01*
G01X1098773Y162898D02*
G03X1099518Y163090I-2J1551D01*
G01X1094324Y161748D02*
X1098772D01*
G01X1094659Y162898D02*
X1098773D01*
G01X1089770Y164646D02*
X1094324Y161748D01*
G01X1090604Y165480D02*
X1094659Y162898D01*
G01X1099868Y163353D02*
X1100266Y163751D01*
G01X1100682Y162539D02*
X1101489Y163346D01*
G01X1099518Y163090D02*
G03X1099868Y163353I-747J1358D01*
G01X1100072Y162081D02*
G03X1100682Y162539I-1301J2367D01*
G01X1098772Y161748D02*
G03X1100072Y162081I1J2701D01*
G01X1098773Y162898D02*
G03X1099518Y163090I-2J1551D01*
G01X1100072Y162081D02*
G03X1100682Y162539I-1301J2367D01*
G01X1098772Y161748D02*
G03X1100072Y162081I1J2701D01*
G01X1094659Y162898D02*
X1098773D01*
G01X1094324Y161748D02*
X1098772D01*
G01X1090604Y165480D02*
X1094659Y162898D01*
G01X1089770Y164646D02*
X1094324Y161748D01*
G01X1093915Y146000D02*
X1089282Y148947D01*
G01X1090115Y149781D02*
X1094250Y147150D01*
G01X1098772Y146000D02*
X1093915D01*
G01X1094250Y147150D02*
X1098773D01*
G01X1100072Y146333D02*
G02X1098772Y146000I-1299J2368D01*
G01X1099518Y147342D02*
G03X1099868Y147605I-747J1358D01*
G01X1098773Y147150D02*
G03X1099518Y147342I-2J1551D01*
G01X1100682Y146791D02*
G02X1100072Y146333I-1911J1909D01*
G01X1099518Y147342D02*
G03X1099868Y147605I-747J1358D01*
G01X1098773Y147150D02*
G03X1099518Y147342I-2J1551D01*
G01X1101489Y147598D02*
X1100682Y146791D01*
G01X1099868Y147605D02*
X1100266Y148003D01*
G01X1099868Y147605D02*
X1100266Y148003D01*
G01X1101489Y147598D02*
X1100682Y146791D01*
G01X1099518Y147342D02*
G03X1099868Y147605I-747J1358D01*
G01X1100072Y146333D02*
G02X1098772Y146000I-1299J2368D01*
G01X1100682Y146791D02*
G02X1100072Y146333I-1911J1909D01*
G01X1098773Y147150D02*
G03X1099518Y147342I-2J1551D01*
G01X1100072Y146333D02*
G02X1098772Y146000I-1299J2368D01*
G01X1100682Y146791D02*
G02X1100072Y146333I-1911J1909D01*
G01X1094250Y147150D02*
X1098773D01*
G01X1098772Y146000D02*
X1093915D01*
G01X1090115Y149781D02*
X1094250Y147150D01*
G01X1093915Y146000D02*
X1089282Y148947D01*
G01X1283636Y109943D02*
X1126539Y210024D01*
G01X1283636Y109943D02*
X1126539Y210024D01*
G01X1283636Y109943D02*
X1126539Y210024D01*
G01X1283636Y109943D02*
X1126539Y210024D01*
G01X1126203Y208874D02*
X1134123Y203828D01*
G01X1283636Y109943D02*
X1126539Y210024D01*
G01X1120890Y208874D02*
X1126203D01*
G01X1126539Y210024D02*
X1121367D01*
G01X1116953Y212811D02*
X1120890Y208874D01*
G01X1121367Y210024D02*
X1117430Y213961D01*
G01X1102888Y212238D02*
G02X1104271Y212811I1383J-1383D01*
G01X1102490Y211840D02*
X1102888Y212238D01*
G01X1102074Y213052D02*
X1101267Y212245D01*
G01X1102074Y213052D02*
X1101267Y212245D01*
G01X1102490Y211840D02*
X1102888Y212238D01*
G01D02*
G02X1104271Y212811I1383J-1383D01*
G01X1121367Y210024D02*
X1117430Y213961D01*
G01X1116953Y212811D02*
X1120890Y208874D01*
G01X1126539Y210024D02*
X1121367D01*
G01X1120890Y208874D02*
X1126203D01*
G01X1283636Y109943D02*
X1126539Y210024D01*
G01X1126203Y208874D02*
X1134123Y203828D01*
G01X1090689Y196162D02*
X1088132Y200174D01*
G01X1093127Y193244D02*
X1089856Y195329D01*
G01X1093463Y194394D02*
X1090689Y196162D01*
G01X1098772Y193244D02*
X1093127D01*
G01X1098773Y194394D02*
X1093463D01*
G01X1100072Y193577D02*
G02X1098772Y193244I-1299J2368D01*
G01X1099518Y194586D02*
G02X1098773Y194394I-747J1358D01*
G01X1099868Y194849D02*
G02X1099518Y194586I-1097J1096D01*
G01X1100682Y194035D02*
G02X1100072Y193577I-1911J1909D01*
G01X1099518Y194586D02*
G02X1098773Y194394I-747J1358D01*
G01X1099868Y194849D02*
G02X1099518Y194586I-1097J1096D01*
G01X1101489Y194842D02*
X1100682Y194035D01*
G01X1100266Y195247D02*
X1099868Y194849D01*
G01X1090689Y196162D02*
X1088132Y200174D01*
G01X1093463Y194394D02*
X1090689Y196162D01*
G01X1093127Y193244D02*
X1089856Y195329D01*
G01X1098773Y194394D02*
X1093463D01*
G01X1098772Y193244D02*
X1093127D01*
G01X1099518Y194586D02*
G02X1098773Y194394I-747J1358D01*
G01X1100072Y193577D02*
G02X1098772Y193244I-1299J2368D01*
G01X1100682Y194035D02*
G02X1100072Y193577I-1911J1909D01*
G01X1099868Y194849D02*
G02X1099518Y194586I-1097J1096D01*
G01X1100072Y193577D02*
G02X1098772Y193244I-1299J2368D01*
G01X1100682Y194035D02*
G02X1100072Y193577I-1911J1909D01*
G01X1100266Y195247D02*
X1099868Y194849D01*
G01X1101489Y194842D02*
X1100682Y194035D01*
G01X1094620Y177496D02*
X1090518Y180108D01*
G01X1091351Y180941D02*
X1094956Y178646D01*
G01X1098772Y177496D02*
X1094620D01*
G01X1094956Y178646D02*
X1098773D01*
G01X1100072Y177829D02*
G02X1098772Y177496I-1299J2368D01*
G01X1099518Y178838D02*
G03X1099868Y179101I-747J1359D01*
G01X1098773Y178646D02*
G03X1099518Y178838I-2J1550D01*
G01X1100682Y178287D02*
G02X1100072Y177829I-1911J1909D01*
G01X1099518Y178838D02*
G03X1099868Y179101I-747J1359D01*
G01X1098773Y178646D02*
G03X1099518Y178838I-2J1550D01*
G01X1101489Y179094D02*
X1100682Y178287D01*
G01X1099868Y179101D02*
X1100266Y179499D01*
G01X1099868Y179101D02*
X1100266Y179499D01*
G01X1101489Y179094D02*
X1100682Y178287D01*
G01X1099518Y178838D02*
G03X1099868Y179101I-747J1359D01*
G01X1100072Y177829D02*
G02X1098772Y177496I-1299J2368D01*
G01X1100682Y178287D02*
G02X1100072Y177829I-1911J1909D01*
G01X1098773Y178646D02*
G03X1099518Y178838I-2J1550D01*
G01X1100072Y177829D02*
G02X1098772Y177496I-1299J2368D01*
G01X1100682Y178287D02*
G02X1100072Y177829I-1911J1909D01*
G01X1094956Y178646D02*
X1098773D01*
G01X1098772Y177496D02*
X1094620D01*
G01X1091351Y180941D02*
X1094956Y178646D01*
G01X1094620Y177496D02*
X1090518Y180108D01*
G01X1125200Y256118D02*
X1150564Y250958D01*
G01X1125316Y257268D02*
X1150917Y252060D01*
G01X1120890Y256118D02*
X1125200D01*
G01X1121367Y257268D02*
X1125316D01*
G01X1116953Y260055D02*
X1120890Y256118D01*
G01X1117430Y261205D02*
X1121367Y257268D01*
G01X1104271Y260055D02*
X1116953D01*
G01X1102888Y259482D02*
G02X1104271Y260055I1383J-1383D01*
G01X1102074Y260296D02*
G02X1104269Y261205I2195J-2195D01*
G01X1102490Y259084D02*
X1102888Y259482D01*
G01X1101267Y259489D02*
X1102074Y260296D01*
G01X1125316Y257268D02*
X1150917Y252060D01*
G01X1125200Y256118D02*
X1150564Y250958D01*
G01X1121367Y257268D02*
X1125316D01*
G01X1120890Y256118D02*
X1125200D01*
G01X1117430Y261205D02*
X1121367Y257268D01*
G01X1116953Y260055D02*
X1120890Y256118D01*
G01X1104271Y260055D02*
X1116953D01*
G01X1102074Y260296D02*
G02X1104269Y261205I2195J-2195D01*
G01X1102888Y259482D02*
G02X1104271Y260055I1383J-1383D01*
G01X1101267Y259489D02*
X1102074Y260296D01*
G01X1102490Y259084D02*
X1102888Y259482D01*
G01X1131760Y240370D02*
X1185817Y228880D01*
G01X1131881Y241520D02*
X1186167Y229982D01*
G01X1120890Y240370D02*
X1131760D01*
G01X1121367Y241520D02*
X1131881D01*
G01X1116953Y244307D02*
X1120890Y240370D01*
G01X1117430Y245457D02*
X1121367Y241520D01*
G01X1104271Y244307D02*
X1116953D01*
G01X1104269Y245457D02*
X1117430D01*
G01X1102888Y243734D02*
G02X1104271Y244307I1383J-1383D01*
G01X1102074Y244548D02*
G02X1104269Y245457I2195J-2195D01*
G01X1102490Y243336D02*
X1102888Y243734D01*
G01X1101267Y243741D02*
X1102074Y244548D01*
G01X1131881Y241520D02*
X1186167Y229982D01*
G01X1131760Y240370D02*
X1185817Y228880D01*
G01X1121367Y241520D02*
X1131881D01*
G01X1120890Y240370D02*
X1131760D01*
G01X1117430Y245457D02*
X1121367Y241520D01*
G01X1116953Y244307D02*
X1120890Y240370D01*
G01X1104269Y245457D02*
X1117430D01*
G01X1104271Y244307D02*
X1116953D01*
G01X1102074Y244548D02*
G02X1104269Y245457I2195J-2195D01*
G01X1102888Y243734D02*
G02X1104271Y244307I1383J-1383D01*
G01X1101267Y243741D02*
X1102074Y244548D01*
G01X1102490Y243336D02*
X1102888Y243734D01*
G01X1124722Y225772D02*
X1155547Y219607D01*
G01X1124722Y225772D02*
X1155547Y219607D01*
G01X1124722Y225772D02*
X1155547Y219607D01*
G01X1133918Y222760D02*
X1135830Y222377D01*
G01X1124722Y225772D02*
X1155547Y219607D01*
G01X1124608Y224622D02*
X1131123Y223319D01*
G01X1124722Y225772D02*
X1155547Y219607D01*
G01X1120890Y224622D02*
X1124608D01*
G01X1121367Y225772D02*
X1124722D01*
G01X1116953Y228559D02*
X1120890Y224622D01*
G01X1117430Y229709D02*
X1121367Y225772D01*
G01X1104271Y228559D02*
X1116953D01*
G01X1104269Y229709D02*
X1117430D01*
G01X1102888Y227986D02*
G02X1104271Y228559I1383J-1383D01*
G01X1102074Y228800D02*
G02X1104269Y229709I2195J-2195D01*
G01X1102490Y227588D02*
X1102888Y227986D01*
G01X1101267Y227993D02*
X1102074Y228800D01*
G01X1124722Y225772D02*
X1155547Y219607D01*
G01X1133918Y222760D02*
X1135830Y222377D01*
G01X1124608Y224622D02*
X1131123Y223319D01*
G01X1121367Y225772D02*
X1124722D01*
G01X1120890Y224622D02*
X1124608D01*
G01X1117430Y229709D02*
X1121367Y225772D01*
G01X1116953Y228559D02*
X1120890Y224622D01*
G01X1104269Y229709D02*
X1117430D01*
G01X1104271Y228559D02*
X1116953D01*
G01X1102074Y228800D02*
G02X1104269Y229709I2195J-2195D01*
G01X1102888Y227986D02*
G02X1104271Y228559I1383J-1383D01*
G01X1101267Y227993D02*
X1102074Y228800D01*
G01X1102490Y227588D02*
X1102888Y227986D01*
G01X1104271Y212811D02*
X1116953D01*
G01X1117430Y213961D02*
X1104269D01*
G01D02*
G03X1102074Y213052I0J-3104D01*
G01X1104269Y213961D02*
G03X1102074Y213052I0J-3104D01*
G01X1117430Y213961D02*
X1104269D01*
G01X1104271Y212811D02*
X1116953D01*
G01X1133826Y303362D02*
X1259432Y276662D01*
G01X1133947Y304512D02*
X1259874Y277744D01*
G01X1120890Y303362D02*
X1133826D01*
G01X1121367Y304512D02*
X1133947D01*
G01X1116953Y307299D02*
X1120890Y303362D01*
G01X1117430Y308449D02*
X1121367Y304512D01*
G01X1104271Y307299D02*
X1116953D01*
G01X1104269Y308449D02*
X1117430D01*
G01X1102888Y306726D02*
G02X1104271Y307299I1383J-1383D01*
G01X1102074Y307540D02*
G02X1104269Y308449I2195J-2195D01*
G01X1102490Y306328D02*
X1102888Y306726D01*
G01X1101267Y306733D02*
X1102074Y307540D01*
G01X1133947Y304512D02*
X1259874Y277744D01*
G01X1133826Y303362D02*
X1259432Y276662D01*
G01X1121367Y304512D02*
X1133947D01*
G01X1120890Y303362D02*
X1133826D01*
G01X1117430Y308449D02*
X1121367Y304512D01*
G01X1116953Y307299D02*
X1120890Y303362D01*
G01X1104269Y308449D02*
X1117430D01*
G01X1104271Y307299D02*
X1116953D01*
G01X1102074Y307540D02*
G02X1104269Y308449I2195J-2195D01*
G01X1102888Y306726D02*
G02X1104271Y307299I1383J-1383D01*
G01X1101267Y306733D02*
X1102074Y307540D01*
G01X1102490Y306328D02*
X1102888Y306726D01*
G01X1125451Y288764D02*
X1164350Y280850D01*
G01X1125451Y288764D02*
X1164350Y280850D01*
G01X1125451Y288764D02*
X1164350Y280850D01*
G01X1125451Y288764D02*
X1164350Y280850D01*
G01X1125335Y287614D02*
X1144183Y283779D01*
G01X1125451Y288764D02*
X1164350Y280850D01*
G01X1120904Y287614D02*
X1125335D01*
G01X1121381Y288764D02*
X1125451D01*
G01X1116967Y291551D02*
X1120904Y287614D01*
G01X1117444Y292701D02*
X1121381Y288764D01*
G01X1104271Y291551D02*
X1116967D01*
G01X1104269Y292701D02*
X1117444D01*
G01X1102888Y290978D02*
G02X1104271Y291551I1383J-1383D01*
G01X1102074Y291792D02*
G02X1104269Y292701I2195J-2195D01*
G01X1102490Y290580D02*
X1102888Y290978D01*
G01X1101267Y290985D02*
X1102074Y291792D01*
G01X1125451Y288764D02*
X1164350Y280850D01*
G01X1125335Y287614D02*
X1144183Y283779D01*
G01X1121381Y288764D02*
X1125451D01*
G01X1120904Y287614D02*
X1125335D01*
G01X1117444Y292701D02*
X1121381Y288764D01*
G01X1116967Y291551D02*
X1120904Y287614D01*
G01X1104269Y292701D02*
X1117444D01*
G01X1104271Y291551D02*
X1116967D01*
G01X1102074Y291792D02*
G02X1104269Y292701I2195J-2195D01*
G01X1102888Y290978D02*
G02X1104271Y291551I1383J-1383D01*
G01X1101267Y290985D02*
X1102074Y291792D01*
G01X1102490Y290580D02*
X1102888Y290978D01*
G01X1131259Y273016D02*
X1345615Y181217D01*
G01X1131259Y273016D02*
X1345615Y181217D01*
G01X1131259Y273016D02*
X1345615Y181217D01*
G01X1131259Y273016D02*
X1345615Y181217D01*
G01X1131023Y271866D02*
X1239492Y225412D01*
G01X1131259Y273016D02*
X1345615Y181217D01*
G01X1120890Y271866D02*
X1131023D01*
G01X1121367Y273016D02*
X1131259D01*
G01X1116953Y275803D02*
X1120890Y271866D01*
G01X1117430Y276953D02*
X1121367Y273016D01*
G01X1104271Y275803D02*
X1116953D01*
G01X1104269Y276953D02*
X1117430D01*
G01X1102888Y275230D02*
G02X1104271Y275803I1383J-1383D01*
G01X1102074Y276044D02*
G02X1104269Y276953I2195J-2195D01*
G01X1102490Y274832D02*
X1102888Y275230D01*
G01X1101267Y275237D02*
X1102074Y276044D01*
G01X1131259Y273016D02*
X1345615Y181217D01*
G01X1131023Y271866D02*
X1239492Y225412D01*
G01X1121367Y273016D02*
X1131259D01*
G01X1120890Y271866D02*
X1131023D01*
G01X1117430Y276953D02*
X1121367Y273016D01*
G01X1116953Y275803D02*
X1120890Y271866D01*
G01X1104269Y276953D02*
X1117430D01*
G01X1104271Y275803D02*
X1116953D01*
G01X1102074Y276044D02*
G02X1104269Y276953I2195J-2195D01*
G01X1102888Y275230D02*
G02X1104271Y275803I1383J-1383D01*
G01X1101267Y275237D02*
X1102074Y276044D01*
G01X1102490Y274832D02*
X1102888Y275230D01*
G01X1104269Y261205D02*
X1117430D01*
G01X1104269D02*
X1117430D01*
G01X1133660Y316318D02*
X1245106Y294657D01*
G01X1133660Y316318D02*
X1245106Y294657D01*
G01X1133660Y316318D02*
X1245106Y294657D01*
G01X1133660Y316318D02*
X1245106Y294657D01*
G01X1133210Y315233D02*
X1137061Y314485D01*
G01X1133660Y316318D02*
X1245106Y294657D01*
G01X1127464Y319110D02*
X1133210Y315233D01*
G01X1127816Y320260D02*
X1133660Y316318D01*
G01X1120663Y319110D02*
X1127464D01*
G01X1121140Y320260D02*
X1127816D01*
G01X1116726Y323047D02*
X1120663Y319110D01*
G01X1117203Y324197D02*
X1121140Y320260D01*
G01X1104271Y323047D02*
X1116726D01*
G01X1104269Y324197D02*
X1117203D01*
G01X1102888Y322474D02*
G02X1104271Y323047I1383J-1383D01*
G01X1102074Y323288D02*
G02X1104269Y324197I2195J-2195D01*
G01X1102490Y322076D02*
X1102888Y322474D01*
G01X1101267Y322481D02*
X1102074Y323288D01*
G01X1133660Y316318D02*
X1245106Y294657D01*
G01X1133210Y315233D02*
X1137061Y314485D01*
G01X1127816Y320260D02*
X1133660Y316318D01*
G01X1127464Y319110D02*
X1133210Y315233D01*
G01X1121140Y320260D02*
X1127816D01*
G01X1120663Y319110D02*
X1127464D01*
G01X1117203Y324197D02*
X1121140Y320260D01*
G01X1116726Y323047D02*
X1120663Y319110D01*
G01X1104269Y324197D02*
X1117203D01*
G01X1104271Y323047D02*
X1116726D01*
G01X1102074Y323288D02*
G02X1104269Y324197I2195J-2195D01*
G01X1102888Y322474D02*
G02X1104271Y323047I1383J-1383D01*
G01X1101267Y322481D02*
X1102074Y323288D01*
G01X1102490Y322076D02*
X1102888Y322474D01*
G01X1109967Y355140D02*
X1194573Y336387D01*
G01X1109967Y353962D02*
X1194126Y335307D01*
G01X1105288Y354103D02*
X1109967Y355140D01*
G01X1105735Y353024D02*
X1109967Y353962D01*
G01X1095866Y348098D02*
X1105288Y354103D01*
G01X1096699Y347265D02*
X1105735Y353024D01*
G01X1089856Y338662D02*
X1095866Y348098D01*
G01X1090943Y338227D02*
X1096699Y347265D01*
G01X1089886Y332859D02*
X1090943Y338227D01*
G01X1088944Y328070D02*
X1089321Y329984D01*
G01X1088002Y323282D02*
X1088378Y325196D01*
G01X1109967Y353962D02*
X1194126Y335307D01*
G01X1109967Y355140D02*
X1194573Y336387D01*
G01X1105735Y353024D02*
X1109967Y353962D01*
G01X1105288Y354103D02*
X1109967Y355140D01*
G01X1096699Y347265D02*
X1105735Y353024D01*
G01X1095866Y348098D02*
X1105288Y354103D01*
G01X1090943Y338227D02*
X1096699Y347265D01*
G01X1089856Y338662D02*
X1095866Y348098D01*
G01X1089886Y332859D02*
X1090943Y338227D01*
G01X1088944Y328070D02*
X1089321Y329984D01*
G01X1088002Y323282D02*
X1088378Y325196D01*
G01X1110422Y361815D02*
X1207696Y341137D01*
G01X1148318Y352583D02*
X1110427Y360638D01*
G01X1091309Y352764D02*
X1102895Y360146D01*
G01X1103342Y359067D02*
X1092142Y351931D01*
G01X1103342Y359067D02*
X1092142Y351931D01*
G01X1091309Y352764D02*
X1102895Y360146D01*
G01X1148318Y352583D02*
X1110427Y360638D01*
G01X1110422Y361815D02*
X1207696Y341137D01*
G01X1110422Y361815D02*
X1207696Y341137D01*
G01X1110422Y361815D02*
X1207696Y341137D01*
G01X1102895Y360146D02*
X1110422Y361815D01*
G01X1110427Y360638D02*
X1103342Y359067D01*
G01X1110427Y360638D02*
X1103342Y359067D01*
G01X1102895Y360146D02*
X1110422Y361815D01*
G01X1114062Y369526D02*
X1099829Y366370D01*
G01X1114062Y368348D02*
X1100276Y365291D01*
G01X1235563Y342587D02*
X1114062Y369526D01*
G01X1115966Y367926D02*
X1114062Y368348D01*
G01X1120730Y366869D02*
X1118826Y367292D01*
G01X1125494Y365813D02*
X1123591Y366235D01*
G01X1130259Y364757D02*
X1128355Y365179D01*
G01X1152333Y359862D02*
X1133119Y364122D01*
G01X1114062Y368348D02*
X1100276Y365291D01*
G01X1114062Y369526D02*
X1099829Y366370D01*
G01X1115966Y367926D02*
X1114062Y368348D01*
G01X1235563Y342587D02*
X1114062Y369526D01*
G01X1120730Y366869D02*
X1118826Y367292D01*
G01X1235563Y342587D02*
X1114062Y369526D01*
G01X1125494Y365813D02*
X1123591Y366235D01*
G01X1235563Y342587D02*
X1114062Y369526D01*
G01X1130259Y364757D02*
X1128355Y365179D01*
G01X1235563Y342587D02*
X1114062Y369526D01*
G01X1152333Y359862D02*
X1133119Y364122D01*
G01X1235563Y342587D02*
X1114062Y369526D01*
G01X1235563Y342587D02*
X1114062Y369526D01*
G01X1235563Y342587D02*
X1114062Y369526D01*
G01X1235563Y342587D02*
X1114062Y369526D01*
G01X1235563Y342587D02*
X1114062Y369526D01*
G01X1235563Y342587D02*
X1114062Y369526D01*
G01X1235563Y342587D02*
X1114062Y369526D01*
G01X1235563Y342587D02*
X1114062Y369526D01*
G01X1235563Y342587D02*
X1114062Y369526D01*
G01X1115629Y376345D02*
X1242069Y348316D01*
G01X1137325Y370357D02*
X1115629Y375167D01*
G01X1095514Y371888D02*
X1115629Y376345D01*
G01Y375167D02*
X1095961Y370809D01*
G01X1115629Y375167D02*
X1095961Y370809D01*
G01X1095514Y371888D02*
X1115629Y376345D01*
G01X1137325Y370357D02*
X1115629Y375167D01*
G01Y376345D02*
X1242069Y348316D01*
G01X1115629Y376345D02*
X1242069Y348316D01*
G01X1115629Y376345D02*
X1242069Y348316D01*
G01X1115629Y376345D02*
X1242069Y348316D01*
G01X1115629Y376345D02*
X1242069Y348316D01*
G01X1115629Y376345D02*
X1242069Y348316D01*
G01X1115629Y376345D02*
X1242069Y348316D01*
G01X1115629Y376345D02*
X1242069Y348316D01*
G01X1115629Y376345D02*
X1242069Y348316D01*
G01X1115629Y376345D02*
X1242069Y348316D01*
G01X1115629Y376345D02*
X1242069Y348316D01*
G01X1115629Y376345D02*
X1242069Y348316D01*
G01X1115629Y376345D02*
X1242069Y348316D01*
G01X1101436Y494890D02*
X1101603Y495224D01*
G01X1100282Y495156D02*
X1100573Y495736D01*
G01X1101238Y494496D02*
X1101436Y494890D01*
G01X1100282Y495156D02*
X1100573Y495736D01*
G01X1099110Y493520D02*
G03X1101238Y494496I-1J2809D01*
G01X1099109Y494670D02*
G03X1100282Y495156I0J1659D01*
G01X1095884Y493520D02*
X1099110D01*
G01X1096290Y494670D02*
X1099109D01*
G01X1089349Y498775D02*
X1095884Y493520D01*
G01X1090216Y499555D02*
X1096290Y494670D01*
G01X1100282Y495156D02*
X1100573Y495736D01*
G01X1101436Y494890D02*
X1101603Y495224D01*
G01X1101238Y494496D02*
X1101436Y494890D01*
G01X1099109Y494670D02*
G03X1100282Y495156I0J1659D01*
G01X1099110Y493520D02*
G03X1101238Y494496I-1J2809D01*
G01X1096290Y494670D02*
X1099109D01*
G01X1095884Y493520D02*
X1099110D01*
G01X1090216Y499555D02*
X1096290Y494670D01*
G01X1089349Y498775D02*
X1095884Y493520D01*
G01X1101436Y479142D02*
X1101603Y479476D01*
G01X1100282Y479408D02*
X1100573Y479988D01*
G01X1101238Y478748D02*
X1101436Y479142D01*
G01X1100282Y479408D02*
X1100573Y479988D01*
G01X1099110Y477772D02*
G03X1101238Y478748I-1J2809D01*
G01X1099109Y478922D02*
G03X1100282Y479408I0J1659D01*
G01X1095615Y477772D02*
X1099110D01*
G01X1096021Y478922D02*
X1099109D01*
G01X1089306Y482845D02*
X1095615Y477772D01*
G01X1090171Y483626D02*
X1096021Y478922D01*
G01X1100282Y479408D02*
X1100573Y479988D01*
G01X1101436Y479142D02*
X1101603Y479476D01*
G01X1101238Y478748D02*
X1101436Y479142D01*
G01X1099109Y478922D02*
G03X1100282Y479408I0J1659D01*
G01X1099110Y477772D02*
G03X1101238Y478748I-1J2809D01*
G01X1096021Y478922D02*
X1099109D01*
G01X1095615Y477772D02*
X1099110D01*
G01X1090171Y483626D02*
X1096021Y478922D01*
G01X1089306Y482845D02*
X1095615Y477772D01*
G01X1101436Y463394D02*
X1101603Y463728D01*
G01X1100282Y463660D02*
X1100573Y464240D01*
G01X1101238Y463000D02*
X1101436Y463394D01*
G01X1100282Y463660D02*
X1100573Y464240D01*
G01X1099110Y462024D02*
G03X1101238Y463000I-1J2809D01*
G01X1099109Y463174D02*
G03X1100282Y463660I0J1659D01*
G01X1095182Y462024D02*
X1099110D01*
G01X1095588Y463174D02*
X1099109D01*
G01X1091804Y464741D02*
X1095182Y462024D01*
G01X1092669Y465522D02*
X1095588Y463174D01*
G01X1088949Y471250D02*
X1092669Y465522D01*
G01X1100282Y463660D02*
X1100573Y464240D01*
G01X1101436Y463394D02*
X1101603Y463728D01*
G01X1101238Y463000D02*
X1101436Y463394D01*
G01X1099109Y463174D02*
G03X1100282Y463660I0J1659D01*
G01X1099110Y462024D02*
G03X1101238Y463000I-1J2809D01*
G01X1095588Y463174D02*
X1099109D01*
G01X1095182Y462024D02*
X1099110D01*
G01X1092669Y465522D02*
X1095588Y463174D01*
G01X1091804Y464741D02*
X1095182Y462024D01*
G01X1088949Y471250D02*
X1092669Y465522D01*
G01X1101436Y510638D02*
X1101603Y510972D01*
G01X1100282Y510904D02*
X1100573Y511484D01*
G01X1101238Y510244D02*
X1101436Y510638D01*
G01X1100282Y510904D02*
X1100573Y511484D01*
G01X1099110Y509268D02*
G03X1101238Y510244I-1J2809D01*
G01X1099109Y510418D02*
G03X1100282Y510904I0J1659D01*
G01X1094459Y509268D02*
X1099110D01*
G01X1094864Y510418D02*
X1099109D01*
G01X1089343Y513381D02*
X1094459Y509268D01*
G01X1090208Y514162D02*
X1094864Y510418D01*
G01X1100282Y510904D02*
X1100573Y511484D01*
G01X1101436Y510638D02*
X1101603Y510972D01*
G01X1101238Y510244D02*
X1101436Y510638D01*
G01X1099109Y510418D02*
G03X1100282Y510904I0J1659D01*
G01X1099110Y509268D02*
G03X1101238Y510244I-1J2809D01*
G01X1094864Y510418D02*
X1099109D01*
G01X1094459Y509268D02*
X1099110D01*
G01X1090208Y514162D02*
X1094864Y510418D01*
G01X1089343Y513381D02*
X1094459Y509268D01*
G01X1101436Y589378D02*
X1101603Y589712D01*
G01X1100282Y589644D02*
X1100573Y590224D01*
G01X1101238Y588984D02*
X1101436Y589378D01*
G01X1100282Y589644D02*
X1100573Y590224D01*
G01X1099110Y588008D02*
G03X1101238Y588984I-1J2809D01*
G01X1099109Y589158D02*
G03X1100282Y589644I0J1659D01*
G01X1094925Y588008D02*
X1099110D01*
G01X1095331Y589158D02*
X1099109D01*
G01X1091479Y592256D02*
X1095331Y589158D01*
G01X1089258Y594043D02*
X1089891Y594111D01*
G01X1100282Y589644D02*
X1100573Y590224D01*
G01X1101436Y589378D02*
X1101603Y589712D01*
G01X1101238Y588984D02*
X1101436Y589378D01*
G01X1099109Y589158D02*
G03X1100282Y589644I0J1659D01*
G01X1099110Y588008D02*
G03X1101238Y588984I-1J2809D01*
G01X1095331Y589158D02*
X1099109D01*
G01X1094925Y588008D02*
X1099110D01*
G01X1091479Y592256D02*
X1095331Y589158D01*
G01X1089258Y594043D02*
X1089891Y594111D01*
G01X1101436Y636622D02*
X1101603Y636956D01*
G01X1100282Y636888D02*
X1100573Y637468D01*
G01X1101238Y636228D02*
X1101436Y636622D01*
G01X1100282Y636888D02*
X1100573Y637468D01*
G01X1099110Y635252D02*
G03X1101238Y636228I-1J2809D01*
G01X1099109Y636402D02*
G03X1100282Y636888I0J1659D01*
G01X1092991Y635252D02*
X1099110D01*
G01X1093397Y636402D02*
X1099109D01*
G01X1100282Y636888D02*
X1100573Y637468D01*
G01X1101436Y636622D02*
X1101603Y636956D01*
G01X1101238Y636228D02*
X1101436Y636622D01*
G01X1099109Y636402D02*
G03X1100282Y636888I0J1659D01*
G01X1099110Y635252D02*
G03X1101238Y636228I-1J2809D01*
G01X1093397Y636402D02*
X1099109D01*
G01X1092991Y635252D02*
X1099110D01*
G01X1100282Y621140D02*
X1100573Y621720D01*
G01X1101436Y620874D02*
X1101603Y621208D01*
G01X1101238Y620480D02*
X1101436Y620874D01*
G01X1099109Y620654D02*
G03X1100282Y621140I0J1659D01*
G01X1099110Y619504D02*
G03X1101238Y620480I-1J2809D01*
G01X1096206Y620654D02*
X1099109D01*
G01X1095800Y619504D02*
X1099110D01*
G01X1101436Y620874D02*
X1101603Y621208D01*
G01X1100282Y621140D02*
X1100573Y621720D01*
G01X1101238Y620480D02*
X1101436Y620874D01*
G01X1100282Y621140D02*
X1100573Y621720D01*
G01X1099110Y619504D02*
G03X1101238Y620480I-1J2809D01*
G01X1099109Y620654D02*
G03X1100282Y621140I0J1659D01*
G01X1095800Y619504D02*
X1099110D01*
G01X1096206Y620654D02*
X1099109D01*
G01X1101436Y605126D02*
X1101603Y605460D01*
G01X1100282Y605392D02*
X1100573Y605972D01*
G01X1101238Y604732D02*
X1101436Y605126D01*
G01X1100282Y605392D02*
X1100573Y605972D01*
G01X1099110Y603756D02*
G03X1101238Y604732I-1J2809D01*
G01X1099109Y604906D02*
G03X1100282Y605392I0J1659D01*
G01X1095800Y603756D02*
X1099110D01*
G01X1096206Y604906D02*
X1099109D01*
G01X1091163Y608962D02*
X1096206Y604906D01*
G01X1088880Y610798D02*
X1089569Y610873D01*
G01X1100282Y605392D02*
X1100573Y605972D01*
G01X1101436Y605126D02*
X1101603Y605460D01*
G01X1101238Y604732D02*
X1101436Y605126D01*
G01X1099109Y604906D02*
G03X1100282Y605392I0J1659D01*
G01X1099110Y603756D02*
G03X1101238Y604732I-1J2809D01*
G01X1096206Y604906D02*
X1099109D01*
G01X1095800Y603756D02*
X1099110D01*
G01X1091163Y608962D02*
X1096206Y604906D01*
G01X1088880Y610798D02*
X1089569Y610873D01*
G01X1099868Y684218D02*
X1100266Y684616D01*
G01X1100682Y683404D02*
X1101489Y684211D01*
G01X1099518Y683955D02*
G03X1099868Y684218I-747J1358D01*
G01X1100072Y682946D02*
G03X1100682Y683404I-1301J2367D01*
G01X1098772Y682613D02*
G03X1100072Y682946I1J2701D01*
G01X1098773Y683763D02*
G03X1099518Y683955I-2J1551D01*
G01X1100072Y682946D02*
G03X1100682Y683404I-1301J2367D01*
G01X1098772Y682613D02*
G03X1100072Y682946I1J2701D01*
G01X1098768Y683763D02*
X1098773D01*
G01X1096008Y682603D02*
X1098772Y682613D01*
G01X1096305Y683755D02*
X1098768Y683763D01*
G01X1096008Y682603D02*
X1098772Y682613D01*
G01X1092483Y685888D02*
X1096305Y683755D01*
G01X1091576Y685077D02*
X1096008Y682603D01*
G01X1100682Y667656D02*
X1101489Y668463D01*
G01X1099868Y668470D02*
X1100266Y668868D01*
G01X1100072Y667198D02*
G03X1100682Y667656I-1301J2367D01*
G01X1099518Y668207D02*
G03X1099868Y668470I-747J1358D01*
G01X1098773Y668015D02*
G03X1099518Y668207I-2J1551D01*
G01X1098772Y666865D02*
G03X1100072Y667198I1J2701D01*
G01X1099518Y668207D02*
G03X1099868Y668470I-747J1358D01*
G01X1098773Y668015D02*
G03X1099518Y668207I-2J1551D01*
G01X1096009Y666855D02*
X1098772Y666865D01*
G01X1098768Y668015D02*
X1098773D01*
G01X1096306Y668007D02*
X1098768Y668015D01*
G01X1090433Y669967D02*
X1096009Y666855D01*
G01X1091340Y670778D02*
X1096306Y668007D01*
G01X1099868Y668470D02*
X1100266Y668868D01*
G01X1100682Y667656D02*
X1101489Y668463D01*
G01X1099518Y668207D02*
G03X1099868Y668470I-747J1358D01*
G01X1100072Y667198D02*
G03X1100682Y667656I-1301J2367D01*
G01X1098772Y666865D02*
G03X1100072Y667198I1J2701D01*
G01X1098773Y668015D02*
G03X1099518Y668207I-2J1551D01*
G01X1100072Y667198D02*
G03X1100682Y667656I-1301J2367D01*
G01X1098772Y666865D02*
G03X1100072Y667198I1J2701D01*
G01X1098768Y668015D02*
X1098773D01*
G01X1096009Y666855D02*
X1098772Y666865D01*
G01X1096306Y668007D02*
X1098768Y668015D01*
G01X1096009Y666855D02*
X1098772Y666865D01*
G01X1091340Y670778D02*
X1096306Y668007D01*
G01X1090433Y669967D02*
X1096009Y666855D01*
G01X1100682Y651908D02*
X1101489Y652715D01*
G01X1099868Y652722D02*
X1100266Y653120D01*
G01X1100072Y651450D02*
G03X1100682Y651908I-1301J2367D01*
G01X1099518Y652459D02*
G03X1099868Y652722I-747J1358D01*
G01X1098773Y652267D02*
G03X1099518Y652459I-2J1551D01*
G01X1098772Y651117D02*
G03X1100072Y651450I1J2701D01*
G01X1099518Y652459D02*
G03X1099868Y652722I-747J1358D01*
G01X1098773Y652267D02*
G03X1099518Y652459I-2J1551D01*
G01X1094934Y651103D02*
X1098772Y651117D01*
G01X1098768Y652267D02*
X1098773D01*
G01X1095230Y652256D02*
X1098768Y652267D01*
G01X1089244Y654279D02*
X1094934Y651103D01*
G01X1090151Y655090D02*
X1095230Y652256D01*
G01X1099868Y652722D02*
X1100266Y653120D01*
G01X1100682Y651908D02*
X1101489Y652715D01*
G01X1099518Y652459D02*
G03X1099868Y652722I-747J1358D01*
G01X1100072Y651450D02*
G03X1100682Y651908I-1301J2367D01*
G01X1098772Y651117D02*
G03X1100072Y651450I1J2701D01*
G01X1098773Y652267D02*
G03X1099518Y652459I-2J1551D01*
G01X1100072Y651450D02*
G03X1100682Y651908I-1301J2367D01*
G01X1098772Y651117D02*
G03X1100072Y651450I1J2701D01*
G01X1098768Y652267D02*
X1098773D01*
G01X1094934Y651103D02*
X1098772Y651117D01*
G01X1095230Y652256D02*
X1098768Y652267D01*
G01X1094934Y651103D02*
X1098772Y651117D01*
G01X1090151Y655090D02*
X1095230Y652256D01*
G01X1089244Y654279D02*
X1094934Y651103D01*
G01X1100682Y683404D02*
X1101489Y684211D01*
G01X1099868Y684218D02*
X1100266Y684616D01*
G01X1100072Y682946D02*
G03X1100682Y683404I-1301J2367D01*
G01X1099518Y683955D02*
G03X1099868Y684218I-747J1358D01*
G01X1098773Y683763D02*
G03X1099518Y683955I-2J1551D01*
G01X1098772Y682613D02*
G03X1100072Y682946I1J2701D01*
G01X1099518Y683955D02*
G03X1099868Y684218I-747J1358D01*
G01X1098773Y683763D02*
G03X1099518Y683955I-2J1551D01*
G01X1096008Y682603D02*
X1098772Y682613D01*
G01X1098768Y683763D02*
X1098773D01*
G01X1096305Y683755D02*
X1098768Y683763D01*
G01X1091576Y685077D02*
X1096008Y682603D01*
G01X1092483Y685888D02*
X1096305Y683755D01*
G01X1099868Y699966D02*
X1100266Y700364D01*
G01X1100682Y699152D02*
X1101489Y699959D01*
G01X1099518Y699703D02*
G03X1099868Y699966I-747J1358D01*
G01X1100072Y698694D02*
G03X1100682Y699152I-1301J2367D01*
G01X1098772Y698361D02*
G03X1100072Y698694I1J2701D01*
G01X1098773Y699511D02*
G03X1099518Y699703I-2J1551D01*
G01X1100072Y698694D02*
G03X1100682Y699152I-1301J2367D01*
G01X1098772Y698361D02*
G03X1100072Y698694I1J2701D01*
G01X1098768Y699511D02*
X1098773D01*
G01X1096009Y698351D02*
X1098772Y698361D01*
G01X1096305Y699503D02*
X1098768Y699511D01*
G01X1096009Y698351D02*
X1098772Y698361D01*
G01X1093713Y700949D02*
X1096305Y699503D01*
G01X1092805Y700138D02*
X1096009Y698351D01*
G01X1101041Y734187D02*
X1090493Y725703D01*
G01X1100487Y735218D02*
X1089477Y726362D01*
G01X1108532Y736580D02*
X1101041Y734187D01*
G01X1108532Y737788D02*
X1100487Y735218D01*
G01X1117349Y733768D02*
X1108532Y736580D01*
G01X1117906Y734798D02*
X1108532Y737788D01*
G01X1125137Y727508D02*
X1117349Y733768D01*
G01X1125989Y728299D02*
X1117906Y734798D01*
G01X1130083Y720313D02*
X1125137Y727508D01*
G01X1457531Y246014D02*
X1125989Y728299D01*
G01X1132802Y716358D02*
X1131698Y717964D01*
G01X1457531Y246014D02*
X1125989Y728299D01*
G01X1135521Y712402D02*
X1134417Y714009D01*
G01X1457531Y246014D02*
X1125989Y728299D01*
G01X1457531Y246014D02*
X1125989Y728299D01*
G01X1457531Y246014D02*
X1125989Y728299D01*
G01X1457531Y246014D02*
X1125989Y728299D01*
G01X1457531Y246014D02*
X1125989Y728299D01*
G01X1457531Y246014D02*
X1125989Y728299D01*
G01X1457531Y246014D02*
X1125989Y728299D01*
G01X1457531Y246014D02*
X1125989Y728299D01*
G01X1457531Y246014D02*
X1125989Y728299D01*
G01X1457531Y246014D02*
X1125989Y728299D01*
G01X1457531Y246014D02*
X1125989Y728299D01*
G01X1457531Y246014D02*
X1125989Y728299D01*
G01X1457531Y246014D02*
X1125989Y728299D01*
G01X1457531Y246014D02*
X1125989Y728299D01*
G01X1457531Y246014D02*
X1125989Y728299D01*
G01X1457531Y246014D02*
X1125989Y728299D01*
G01X1457531Y246014D02*
X1125989Y728299D01*
G01X1457531Y246014D02*
X1125989Y728299D01*
G01X1457531Y246014D02*
X1125989Y728299D01*
G01X1457531Y246014D02*
X1125989Y728299D01*
G01X1457531Y246014D02*
X1125989Y728299D01*
G01X1457531Y246014D02*
X1125989Y728299D01*
G01X1100682Y699152D02*
X1101489Y699959D01*
G01X1099868Y699966D02*
X1100266Y700364D01*
G01X1100072Y698694D02*
G03X1100682Y699152I-1301J2367D01*
G01X1099518Y699703D02*
G03X1099868Y699966I-747J1358D01*
G01X1098773Y699511D02*
G03X1099518Y699703I-2J1551D01*
G01X1098772Y698361D02*
G03X1100072Y698694I1J2701D01*
G01X1099518Y699703D02*
G03X1099868Y699966I-747J1358D01*
G01X1098773Y699511D02*
G03X1099518Y699703I-2J1551D01*
G01X1096009Y698351D02*
X1098772Y698361D01*
G01X1098768Y699511D02*
X1098773D01*
G01X1096305Y699503D02*
X1098768Y699511D01*
G01X1092805Y700138D02*
X1096009Y698351D01*
G01X1093713Y700949D02*
X1096305Y699503D01*
G01X1100487Y735218D02*
X1089477Y726362D01*
G01X1101041Y734187D02*
X1090493Y725703D01*
G01X1108532Y737788D02*
X1100487Y735218D01*
G01X1108532Y736580D02*
X1101041Y734187D01*
G01X1117906Y734798D02*
X1108532Y737788D01*
G01X1117349Y733768D02*
X1108532Y736580D01*
G01X1125989Y728299D02*
X1117906Y734798D01*
G01X1125137Y727508D02*
X1117349Y733768D01*
G01X1457531Y246014D02*
X1125989Y728299D01*
G01X1130083Y720313D02*
X1125137Y727508D01*
G01X1132802Y716358D02*
X1131698Y717964D01*
G01X1135521Y712402D02*
X1134417Y714009D01*
G01X1108161Y743301D02*
X1098018Y740062D01*
G01X1108161Y744509D02*
X1097464Y741093D01*
G01X1120705Y739300D02*
X1108161Y743301D01*
G01X1114782Y742397D02*
X1108161Y744509D01*
G01X1121259Y740331D02*
X1114782Y742397D01*
G01X1131242Y730829D02*
X1120705Y739300D01*
G01X1132095Y731620D02*
X1121259Y740331D01*
G01X1135594Y724495D02*
X1131242Y730829D01*
G01X1462079Y251419D02*
X1132095Y731620D01*
G01X1462079Y251419D02*
X1132095Y731620D01*
G01X1462079Y251419D02*
X1132095Y731620D01*
G01X1462079Y251419D02*
X1132095Y731620D01*
G01X1462079Y251419D02*
X1132095Y731620D01*
G01X1462079Y251419D02*
X1132095Y731620D01*
G01X1462079Y251419D02*
X1132095Y731620D01*
G01X1462079Y251419D02*
X1132095Y731620D01*
G01X1462079Y251419D02*
X1132095Y731620D01*
G01X1462079Y251419D02*
X1132095Y731620D01*
G01X1462079Y251419D02*
X1132095Y731620D01*
G01X1462079Y251419D02*
X1132095Y731620D01*
G01X1462079Y251419D02*
X1132095Y731620D01*
G01X1462079Y251419D02*
X1132095Y731620D01*
G01X1462079Y251419D02*
X1132095Y731620D01*
G01X1462079Y251419D02*
X1132095Y731620D01*
G01X1462079Y251419D02*
X1132095Y731620D01*
G01X1462079Y251419D02*
X1132095Y731620D01*
G01X1462079Y251419D02*
X1132095Y731620D01*
G01X1462079Y251419D02*
X1132095Y731620D01*
G01X1462079Y251419D02*
X1132095Y731620D01*
G01X1462079Y251419D02*
X1132095Y731620D01*
G01X1462079Y251419D02*
X1132095Y731620D01*
G01X1462079Y251419D02*
X1132095Y731620D01*
G01X1139542Y733837D02*
X1123229Y746950D01*
G01X1138690Y733046D02*
X1122675Y745919D01*
G01X1138690Y733046D02*
X1122675Y745919D01*
G01X1139542Y733837D02*
X1123229Y746950D01*
G01X1149743Y732265D02*
X1125645Y751637D01*
G01X1149743Y732265D02*
X1125645Y751637D01*
G01X1108161Y744509D02*
X1097464Y741093D01*
G01X1108161Y743301D02*
X1098018Y740062D01*
G01X1114782Y742397D02*
X1108161Y744509D01*
G01X1120705Y739300D02*
X1108161Y743301D01*
G01X1121259Y740331D02*
X1114782Y742397D01*
G01X1120705Y739300D02*
X1108161Y743301D01*
G01X1132095Y731620D02*
X1121259Y740331D01*
G01X1131242Y730829D02*
X1120705Y739300D01*
G01X1462079Y251419D02*
X1132095Y731620D01*
G01X1135594Y724495D02*
X1131242Y730829D01*
G01X1109116Y751455D02*
X1094655Y746837D01*
G01X1109116Y750247D02*
X1095209Y745806D01*
G01X1123229Y746950D02*
X1109116Y751455D01*
G01X1122675Y745919D02*
X1109116Y750247D01*
G01D02*
X1095209Y745806D01*
G01X1109116Y751455D02*
X1094655Y746837D01*
G01X1122675Y745919D02*
X1109116Y750247D01*
G01X1123229Y746950D02*
X1109116Y751455D01*
G01X1093113Y753527D02*
X1092908Y753461D01*
G01X1108339Y757176D02*
X1093462Y752429D01*
G01X1108340Y758384D02*
X1093113Y753527D01*
G01X1108339Y757176D02*
X1093462Y752429D01*
G01X1126199Y752668D02*
X1108340Y758384D01*
G01X1125645Y751637D02*
X1108339Y757176D01*
G01X1150595Y733056D02*
X1126199Y752668D01*
G01X1108339Y757176D02*
X1093462Y752429D01*
G01X1093113Y753527D02*
X1092908Y753461D01*
G01X1108340Y758384D02*
X1093113Y753527D01*
G01X1125645Y751637D02*
X1108339Y757176D01*
G01X1126199Y752668D02*
X1108340Y758384D01*
G01X1150595Y733056D02*
X1126199Y752668D01*
G01X1155298Y218481D02*
X1400287Y122718D01*
G01X1155648Y219581D02*
X1401011Y123670D01*
G01X1155648Y219581D02*
X1401011Y123670D01*
G01X1155298Y218481D02*
X1400287Y122718D01*
G01X1148672Y194560D02*
X1283189Y108864D01*
G01X1144624Y197139D02*
X1146268Y196091D01*
G01X1140575Y199718D02*
X1142220Y198670D01*
G01X1136527Y202297D02*
X1138172Y201249D01*
G01X1148672Y194560D02*
X1283189Y108864D01*
G01X1144624Y197139D02*
X1146268Y196091D01*
G01X1140575Y199718D02*
X1142220Y198670D01*
G01X1136527Y202297D02*
X1138172Y201249D01*
G01X1150917Y252059D02*
X1369752Y158342D01*
G01X1168508Y243274D02*
X1369211Y157322D01*
G01X1150917Y252059D02*
X1369752Y158342D01*
G01X1164022Y245195D02*
X1165814Y244427D01*
G01X1150917Y252059D02*
X1369752Y158342D01*
G01X1159536Y247116D02*
X1161328Y246348D01*
G01X1150917Y252059D02*
X1369752Y158342D01*
G01X1155050Y249037D02*
X1156842Y248269D01*
G01X1150917Y252059D02*
X1369752Y158342D01*
G01X1150564Y250958D02*
X1152357Y250190D01*
G01X1150917Y252059D02*
X1369752Y158342D01*
G01X1150917Y252059D02*
X1369752Y158342D01*
G01X1168508Y243274D02*
X1369211Y157322D01*
G01X1164022Y245195D02*
X1165814Y244427D01*
G01X1159536Y247116D02*
X1161328Y246348D01*
G01X1155050Y249037D02*
X1156842Y248269D01*
G01X1150564Y250958D02*
X1152357Y250190D01*
G01X1148038Y219935D02*
X1155294Y218484D01*
G01X1155547Y219607D02*
X1155648Y219581D01*
G01X1143331Y220877D02*
X1145243Y220494D01*
G01X1138625Y221818D02*
X1140537Y221436D01*
G01X1155547Y219607D02*
X1155648Y219581D01*
G01X1148038Y219935D02*
X1155294Y218484D01*
G01X1148038Y219935D02*
X1155294Y218484D01*
G01X1143331Y220877D02*
X1145243Y220494D01*
G01X1138625Y221818D02*
X1140537Y221436D01*
G01X1153994Y311193D02*
X1244672Y293569D01*
G01X1153994Y311193D02*
X1244672Y293569D01*
G01X1163969Y279753D02*
X1371444Y175092D01*
G01X1164350Y280850D02*
X1371833Y176184D01*
G01X1161400Y280276D02*
X1163969Y279753D01*
G01X1156618Y281249D02*
X1158529Y280860D01*
G01X1151836Y282222D02*
X1153747Y281833D01*
G01X1147054Y283195D02*
X1148965Y282806D01*
G01X1164350Y280850D02*
X1371833Y176184D01*
G01X1163969Y279753D02*
X1371444Y175092D01*
G01X1161400Y280276D02*
X1163969Y279753D01*
G01X1156618Y281249D02*
X1158529Y280860D01*
G01X1151836Y282222D02*
X1153747Y281833D01*
G01X1147054Y283195D02*
X1148965Y282806D01*
G01X1149282Y312109D02*
X1151196Y311737D01*
G01X1144570Y313025D02*
X1146485Y312653D01*
G01X1139859Y313941D02*
X1141773Y313569D01*
G01X1149282Y312109D02*
X1151196Y311737D01*
G01X1144570Y313025D02*
X1146485Y312653D01*
G01X1139859Y313941D02*
X1141773Y313569D01*
G01X1153091Y351569D02*
X1151184Y351974D01*
G01X1207248Y340056D02*
X1155957Y350959D01*
G01X1153091Y351569D02*
X1151184Y351974D01*
G01X1207248Y340056D02*
X1155957Y350959D01*
G01X1166391Y356745D02*
X1164487Y357167D01*
G01X1188699Y351799D02*
X1169173Y356128D01*
G01X1166391Y356745D02*
X1164487Y357167D01*
G01X1188699Y351799D02*
X1169173Y356128D01*
G01X1157019Y358823D02*
X1155115Y359245D01*
G01X1161705Y357784D02*
X1159801Y358206D01*
G01X1157019Y358823D02*
X1155115Y359245D01*
G01X1161705Y357784D02*
X1159801Y358206D01*
G01X1142090Y369301D02*
X1140186Y369723D01*
G01X1146854Y368245D02*
X1144950Y368667D01*
G01X1151618Y367188D02*
X1149715Y367610D01*
G01X1186484Y359459D02*
X1154479Y366554D01*
G01X1142090Y369301D02*
X1140186Y369723D01*
G01X1146854Y368245D02*
X1144950Y368667D01*
G01X1151618Y367188D02*
X1149715Y367610D01*
G01X1186484Y359459D02*
X1154479Y366554D01*
G01X1196830Y623217D02*
X1175305Y654529D01*
G01X1196830Y623217D02*
X1175305Y654529D01*
G01X1165352Y669008D02*
X1139855Y706098D01*
G01X1168116Y664986D02*
X1167012Y666593D01*
G01X1170881Y660965D02*
X1169776Y662572D01*
G01X1173645Y656944D02*
X1172541Y658551D01*
G01X1165352Y669008D02*
X1139855Y706098D01*
G01X1168116Y664986D02*
X1167012Y666593D01*
G01X1170881Y660965D02*
X1169776Y662572D01*
G01X1173645Y656944D02*
X1172541Y658551D01*
G01X1171450Y672317D02*
X1145364Y710278D01*
G01X1174213Y668295D02*
X1173109Y669903D01*
G01X1176977Y664274D02*
X1175873Y665881D01*
G01X1179741Y660252D02*
X1178637Y661859D01*
G01X1233431Y582120D02*
X1181400Y657837D01*
G01X1465442Y259694D02*
X1139542Y733837D01*
G01X1178205Y675555D02*
X1152435Y713048D01*
G01X1180969Y671534D02*
X1179865Y673141D01*
G01X1183733Y667512D02*
X1182629Y669119D01*
G01X1465442Y259694D02*
X1139542Y733837D01*
G01X1465442Y259694D02*
X1139542Y733837D01*
G01X1465442Y259694D02*
X1139542Y733837D01*
G01X1465442Y259694D02*
X1139542Y733837D01*
G01X1178205Y675555D02*
X1152435Y713048D01*
G01X1465442Y259694D02*
X1139542Y733837D01*
G01X1180969Y671534D02*
X1179865Y673141D01*
G01X1465442Y259694D02*
X1139542Y733837D01*
G01X1183733Y667512D02*
X1182629Y669119D01*
G01X1465442Y259694D02*
X1139542Y733837D01*
G01X1465442Y259694D02*
X1139542Y733837D01*
G01X1465442Y259694D02*
X1139542Y733837D01*
G01X1465442Y259694D02*
X1139542Y733837D01*
G01X1465442Y259694D02*
X1139542Y733837D01*
G01X1465442Y259694D02*
X1139542Y733837D01*
G01X1465442Y259694D02*
X1139542Y733837D01*
G01X1465442Y259694D02*
X1139542Y733837D01*
G01X1465442Y259694D02*
X1139542Y733837D01*
G01X1465442Y259694D02*
X1139542Y733837D01*
G01X1465442Y259694D02*
X1139542Y733837D01*
G01X1465442Y259694D02*
X1139542Y733837D01*
G01X1465442Y259694D02*
X1139542Y733837D01*
G01X1465442Y259694D02*
X1139542Y733837D01*
G01X1465442Y259694D02*
X1139542Y733837D01*
G01X1465442Y259694D02*
X1139542Y733837D01*
G01X1465442Y259694D02*
X1139542Y733837D01*
G01X1465442Y259694D02*
X1139542Y733837D01*
G01X1503552Y219868D02*
X1150595Y733056D01*
G01X1185191Y680724D02*
X1160826Y716150D01*
G01X1503552Y219868D02*
X1150595Y733056D01*
G01X1503552Y219868D02*
X1150595Y733056D01*
G01X1503552Y219868D02*
X1150595Y733056D01*
G01X1503552Y219868D02*
X1150595Y733056D01*
G01X1185191Y680724D02*
X1160826Y716150D01*
G01X1503552Y219868D02*
X1150595Y733056D01*
G01X1503552Y219868D02*
X1150595Y733056D01*
G01X1503552Y219868D02*
X1150595Y733056D01*
G01X1503552Y219868D02*
X1150595Y733056D01*
G01X1503552Y219868D02*
X1150595Y733056D01*
G01X1503552Y219868D02*
X1150595Y733056D01*
G01X1503552Y219868D02*
X1150595Y733056D01*
G01X1503552Y219868D02*
X1150595Y733056D01*
G01X1503552Y219868D02*
X1150595Y733056D01*
G01X1503552Y219868D02*
X1150595Y733056D01*
G01X1503552Y219868D02*
X1150595Y733056D01*
G01X1503552Y219868D02*
X1150595Y733056D01*
G01X1503552Y219868D02*
X1150595Y733056D01*
G01X1503552Y219868D02*
X1150595Y733056D01*
G01X1503552Y219868D02*
X1150595Y733056D01*
G01X1503552Y219868D02*
X1150595Y733056D01*
G01X1503552Y219868D02*
X1150595Y733056D01*
G01X1503552Y219868D02*
X1150595Y733056D01*
G01X1503552Y219868D02*
X1150595Y733056D01*
G01X1503552Y219868D02*
X1150595Y733056D01*
G01X1171450Y672317D02*
X1145364Y710278D01*
G01X1174213Y668295D02*
X1173109Y669903D01*
G01X1176977Y664274D02*
X1175873Y665881D01*
G01X1179741Y660252D02*
X1178637Y661859D01*
G01X1233431Y582120D02*
X1181400Y657837D01*
G01X1138241Y708446D02*
X1137136Y710053D01*
G01X1138241Y708446D02*
X1137136Y710053D01*
G01X1138313Y720539D02*
X1137208Y722146D01*
G01X1141031Y716583D02*
X1139927Y718190D01*
G01X1143750Y712627D02*
X1142645Y714234D01*
G01X1142664Y727264D02*
X1138690Y733046D01*
G01X1145383Y723308D02*
X1144279Y724915D01*
G01X1148102Y719352D02*
X1146998Y720959D01*
G01X1150821Y715396D02*
X1149717Y717003D01*
G01X1142664Y727264D02*
X1138690Y733046D01*
G01X1145383Y723308D02*
X1144279Y724915D01*
G01X1148102Y719352D02*
X1146998Y720959D01*
G01X1150821Y715396D02*
X1149717Y717003D01*
G01X1151051Y730363D02*
X1149743Y732265D01*
G01X1153771Y726408D02*
X1152666Y728015D01*
G01X1156491Y722453D02*
X1155386Y724060D01*
G01X1159211Y718499D02*
X1158106Y720105D01*
G01X1151051Y730363D02*
X1149743Y732265D01*
G01X1153771Y726408D02*
X1152666Y728015D01*
G01X1156491Y722453D02*
X1155386Y724060D01*
G01X1159211Y718499D02*
X1158106Y720105D01*
G01X1138313Y720539D02*
X1137208Y722146D01*
G01X1141031Y716583D02*
X1139927Y718190D01*
G01X1143750Y712627D02*
X1142645Y714234D01*
G01X1208334Y219237D02*
X1366580Y151464D01*
G01X1186167Y229982D02*
X1367119Y152485D01*
G01X1186167Y229982D02*
X1367119Y152485D01*
G01X1186167Y229982D02*
X1367119Y152485D01*
G01X1186167Y229982D02*
X1367119Y152485D01*
G01X1186167Y229982D02*
X1367119Y152485D01*
G01X1186167Y229982D02*
X1367119Y152485D01*
G01X1208334Y219237D02*
X1366580Y151464D01*
G01X1203848Y221158D02*
X1205640Y220390D01*
G01X1199362Y223079D02*
X1201154Y222311D01*
G01X1194876Y225000D02*
X1196668Y224233D01*
G01X1185817Y228880D02*
X1192183Y226154D01*
G01X1203848Y221158D02*
X1205640Y220390D01*
G01X1199362Y223079D02*
X1201154Y222311D01*
G01X1194876Y225000D02*
X1196668Y224233D01*
G01X1185817Y228880D02*
X1192183Y226154D01*
G01X1194573Y336387D02*
X1406537Y201347D01*
G01X1209260Y325666D02*
X1256941Y295289D01*
G01X1205212Y328245D02*
X1206856Y327197D01*
G01X1201163Y330824D02*
X1202808Y329776D01*
G01X1197115Y333403D02*
X1198760Y332355D01*
G01X1194126Y335307D02*
X1194711Y334935D01*
G01X1194573Y336387D02*
X1406537Y201347D01*
G01X1194573Y336387D02*
X1406537Y201347D01*
G01X1194573Y336387D02*
X1406537Y201347D01*
G01X1194573Y336387D02*
X1406537Y201347D01*
G01X1194573Y336387D02*
X1406537Y201347D01*
G01X1194573Y336387D02*
X1406537Y201347D01*
G01X1194573Y336387D02*
X1406537Y201347D01*
G01X1209260Y325666D02*
X1256941Y295289D01*
G01X1194573Y336387D02*
X1406537Y201347D01*
G01X1205212Y328245D02*
X1206856Y327197D01*
G01X1194573Y336387D02*
X1406537Y201347D01*
G01X1201163Y330824D02*
X1202808Y329776D01*
G01X1194573Y336387D02*
X1406537Y201347D01*
G01X1197115Y333403D02*
X1198760Y332355D01*
G01X1194573Y336387D02*
X1406537Y201347D01*
G01X1194126Y335307D02*
X1194711Y334935D01*
G01X1194573Y336387D02*
X1406537Y201347D01*
G01X1207696Y341137D02*
X1409654Y209985D01*
G01X1208883Y338994D02*
X1207248Y340056D01*
G01X1212976Y336336D02*
X1211341Y337398D01*
G01X1217069Y333678D02*
X1215433Y334740D01*
G01X1221162Y331020D02*
X1219526Y332082D01*
G01X1264378Y302956D02*
X1223619Y329425D01*
G01X1208883Y338994D02*
X1207248Y340056D01*
G01X1207696Y341137D02*
X1409654Y209985D01*
G01X1212976Y336336D02*
X1211341Y337398D01*
G01X1207696Y341137D02*
X1409654Y209985D01*
G01X1217069Y333678D02*
X1215433Y334740D01*
G01X1207696Y341137D02*
X1409654Y209985D01*
G01X1221162Y331020D02*
X1219526Y332082D01*
G01X1207696Y341137D02*
X1409654Y209985D01*
G01X1264378Y302956D02*
X1223619Y329425D01*
G01X1207696Y341137D02*
X1409654Y209985D01*
G01X1207696Y341137D02*
X1409654Y209985D01*
G01X1207696Y341137D02*
X1409654Y209985D01*
G01X1207696Y341137D02*
X1409654Y209985D01*
G01X1207696Y341137D02*
X1409654Y209985D01*
G01X1207696Y341137D02*
X1409654Y209985D01*
G01X1207696Y341137D02*
X1409654Y209985D01*
G01X1207696Y341137D02*
X1409654Y209985D01*
G01X1207696Y341137D02*
X1409654Y209985D01*
G01X1193385Y350760D02*
X1191482Y351182D01*
G01X1198072Y349720D02*
X1196168Y350143D01*
G01X1202758Y348681D02*
X1200854Y349103D01*
G01X1235090Y341513D02*
X1205540Y348064D01*
G01X1193385Y350760D02*
X1191482Y351182D01*
G01X1198072Y349720D02*
X1196168Y350143D01*
G01X1202758Y348681D02*
X1200854Y349103D01*
G01X1235090Y341513D02*
X1205540Y348064D01*
G01X1195856Y357381D02*
X1193953Y357803D01*
G01X1200543Y356343D02*
X1198639Y356765D01*
G01X1222851Y351397D02*
X1203325Y355726D01*
G01X1227537Y350358D02*
X1225633Y350781D01*
G01X1232224Y349320D02*
X1230320Y349742D01*
G01X1195856Y357381D02*
X1193953Y357803D01*
G01X1200543Y356343D02*
X1198639Y356765D01*
G01X1222851Y351397D02*
X1203325Y355726D01*
G01X1227537Y350358D02*
X1225633Y350781D01*
G01X1232224Y349320D02*
X1230320Y349742D01*
G01X1191170Y358420D02*
X1189266Y358842D01*
G01X1191170Y358420D02*
X1189266Y358842D01*
G01X1227467Y578649D02*
X1206602Y609002D01*
G01X1230187Y574694D02*
X1229082Y576301D01*
G01X1232906Y570738D02*
X1231801Y572345D01*
G01X1227467Y578649D02*
X1206602Y609002D01*
G01X1230187Y574694D02*
X1229082Y576301D01*
G01X1232906Y570738D02*
X1231801Y572345D01*
G01X1240293Y585226D02*
X1219527Y615437D01*
G01X1240293Y585226D02*
X1219527Y615437D01*
G01X1199549Y619261D02*
X1198445Y620868D01*
G01X1202269Y615306D02*
X1201164Y616913D01*
G01X1204988Y611350D02*
X1203883Y612957D01*
G01X1199549Y619261D02*
X1198445Y620868D01*
G01X1202269Y615306D02*
X1201164Y616913D01*
G01X1204988Y611350D02*
X1203883Y612957D01*
G01X1209755Y629653D02*
X1188157Y661076D01*
G01X1212474Y625697D02*
X1211370Y627304D01*
G01X1215193Y621742D02*
X1214089Y623349D01*
G01X1217912Y617786D02*
X1216808Y619393D01*
G01X1209755Y629653D02*
X1188157Y661076D01*
G01X1212474Y625697D02*
X1211370Y627304D01*
G01X1215193Y621742D02*
X1214089Y623349D01*
G01X1217912Y617786D02*
X1216808Y619393D01*
G01X1216750Y634837D02*
X1195147Y666248D01*
G01X1219470Y630882D02*
X1218365Y632489D01*
G01X1222190Y626927D02*
X1221085Y628534D01*
G01X1224910Y622973D02*
X1223805Y624579D01*
G01X1247018Y590827D02*
X1226525Y620624D01*
G01X1216750Y634837D02*
X1195147Y666248D01*
G01X1219470Y630882D02*
X1218365Y632489D01*
G01X1222190Y626927D02*
X1221085Y628534D01*
G01X1224910Y622973D02*
X1223805Y624579D01*
G01X1247018Y590827D02*
X1226525Y620624D01*
G01X1186498Y663490D02*
X1185393Y665097D01*
G01X1186498Y663490D02*
X1185393Y665097D01*
G01X1187956Y676703D02*
X1186851Y678310D01*
G01X1190722Y672683D02*
X1189616Y674289D01*
G01X1193487Y668662D02*
X1192382Y670268D01*
G01X1187956Y676703D02*
X1186851Y678310D01*
G01X1190722Y672683D02*
X1189616Y674289D01*
G01X1193487Y668662D02*
X1192382Y670268D01*
G01X1255643Y218496D02*
X1345076Y180196D01*
G01X1255643Y218496D02*
X1345076Y180196D01*
G01X1251157Y220417D02*
X1252949Y219649D01*
G01X1246671Y222338D02*
X1248463Y221570D01*
G01X1242185Y224259D02*
X1243977Y223491D01*
G01X1251157Y220417D02*
X1252949Y219649D01*
G01X1246671Y222338D02*
X1248463Y221570D01*
G01X1242185Y224259D02*
X1243977Y223491D01*
G01X1244672Y293569D02*
X1379718Y207554D01*
G01X1245106Y294657D02*
X1380551Y208387D01*
G01X1245106Y294657D02*
X1380551Y208387D01*
G01X1244672Y293569D02*
X1379718Y207554D01*
G01X1259874Y277744D02*
X1375398Y204152D01*
G01X1259874Y277744D02*
X1375398Y204152D01*
G01X1259874Y277744D02*
X1375398Y204152D01*
G01X1259874Y277744D02*
X1375398Y204152D01*
G01X1259432Y276662D02*
X1352985Y217066D01*
G01X1259874Y277744D02*
X1375398Y204152D01*
G01X1259874Y277744D02*
X1375398Y204152D01*
G01X1259432Y276662D02*
X1352985Y217066D01*
G01X1271489Y286020D02*
X1296150Y270309D01*
G01X1267441Y288599D02*
X1269085Y287552D01*
G01X1263393Y291178D02*
X1265037Y290131D01*
G01X1259344Y293758D02*
X1260989Y292710D01*
G01X1271489Y286020D02*
X1296150Y270309D01*
G01X1267441Y288599D02*
X1269085Y287552D01*
G01X1263393Y291178D02*
X1265037Y290131D01*
G01X1259344Y293758D02*
X1260989Y292710D01*
G01X1268471Y300298D02*
X1266836Y301360D01*
G01X1272564Y297640D02*
X1270928Y298702D01*
G01X1276656Y294982D02*
X1275021Y296044D01*
G01X1313442Y271093D02*
X1279114Y293386D01*
G01X1268471Y300298D02*
X1266836Y301360D01*
G01X1272564Y297640D02*
X1270928Y298702D01*
G01X1276656Y294982D02*
X1275021Y296044D01*
G01X1313442Y271093D02*
X1279114Y293386D01*
G01X1465157Y180124D02*
X1246879Y333243D01*
G01X1465157Y180124D02*
X1246879Y333243D01*
G01X1466004Y180935D02*
X1235563Y342587D01*
G01X1236686Y340393D02*
X1235090Y341513D01*
G01X1239020Y338756D02*
X1238393Y338646D01*
G01X1240616Y337637D02*
X1239020Y338756D01*
G01X1242949Y336000D02*
X1242322Y335890D01*
G01X1244545Y334880D02*
X1242949Y336000D01*
G01X1246879Y333243D02*
X1246252Y333133D01*
G01X1236686Y340393D02*
X1235090Y341513D01*
G01X1466004Y180935D02*
X1235563Y342587D01*
G01X1239020Y338756D02*
X1238393Y338646D01*
G01X1466004Y180935D02*
X1235563Y342587D01*
G01X1240616Y337637D02*
X1239020Y338756D01*
G01X1466004Y180935D02*
X1235563Y342587D01*
G01X1242949Y336000D02*
X1242322Y335890D01*
G01X1466004Y180935D02*
X1235563Y342587D01*
G01X1244545Y334880D02*
X1242949Y336000D01*
G01X1466004Y180935D02*
X1235563Y342587D01*
G01X1246879Y333243D02*
X1246252Y333133D01*
G01X1466004Y180935D02*
X1235563Y342587D01*
G01X1466004Y180935D02*
X1235563Y342587D01*
G01X1242069Y348316D02*
X1467793Y189972D01*
G01X1244497Y345207D02*
X1241596Y347242D01*
G01X1246830Y343571D02*
X1246203Y343461D01*
G01X1248426Y342451D02*
X1246830Y343571D01*
G01X1250759Y340814D02*
X1250132Y340704D01*
G01X1252356Y339694D02*
X1250759Y340814D01*
G01X1254689Y338058D02*
X1254062Y337948D01*
G01X1466946Y189161D02*
X1254689Y338058D01*
G01X1236910Y348281D02*
X1235006Y348703D01*
G01X1241596Y347242D02*
X1239692Y347664D01*
G01X1236910Y348281D02*
X1235006Y348703D01*
G01X1241596Y347242D02*
X1239692Y347664D01*
G01X1244497Y345207D02*
X1241596Y347242D01*
G01X1242069Y348316D02*
X1467793Y189972D01*
G01X1246830Y343571D02*
X1246203Y343461D01*
G01X1242069Y348316D02*
X1467793Y189972D01*
G01X1248426Y342451D02*
X1246830Y343571D01*
G01X1242069Y348316D02*
X1467793Y189972D01*
G01X1250759Y340814D02*
X1250132Y340704D01*
G01X1242069Y348316D02*
X1467793Y189972D01*
G01X1252356Y339694D02*
X1250759Y340814D01*
G01X1242069Y348316D02*
X1467793Y189972D01*
G01X1254689Y338058D02*
X1254062Y337948D01*
G01X1242069Y348316D02*
X1467793Y189972D01*
G01X1466946Y189161D02*
X1254689Y338058D01*
G01X1242069Y348316D02*
X1467793Y189972D01*
G01X1279741Y502607D02*
X1278636Y504214D01*
G01X1310862Y457335D02*
X1281355Y500259D01*
G01X1279741Y502607D02*
X1278636Y504214D01*
G01X1310862Y457335D02*
X1281355Y500259D01*
G01X1271583Y514474D02*
X1237239Y564434D01*
G01X1274303Y510518D02*
X1273198Y512125D01*
G01X1277022Y506563D02*
X1275917Y508170D01*
G01X1271583Y514474D02*
X1237239Y564434D01*
G01X1274303Y510518D02*
X1273198Y512125D01*
G01X1277022Y506563D02*
X1275917Y508170D01*
G01X1277551Y517916D02*
X1243201Y567903D01*
G01X1280270Y513960D02*
X1279165Y515567D01*
G01X1283981Y521665D02*
X1250064Y571010D01*
G01X1283981Y521665D02*
X1250064Y571010D01*
G01X1290945Y526960D02*
X1256794Y576614D01*
G01X1290945Y526960D02*
X1256794Y576614D01*
G01X1277551Y517916D02*
X1243201Y567903D01*
G01X1280270Y513960D02*
X1279165Y515567D01*
G01X1235625Y566783D02*
X1234520Y568390D01*
G01X1235625Y566783D02*
X1234520Y568390D01*
G01X1236150Y578164D02*
X1235045Y579771D01*
G01X1238868Y574208D02*
X1237764Y575815D01*
G01X1241587Y570252D02*
X1240482Y571859D01*
G01X1243012Y581270D02*
X1241907Y582877D01*
G01X1245731Y577314D02*
X1244626Y578921D01*
G01X1248450Y573359D02*
X1247345Y574966D01*
G01X1243012Y581270D02*
X1241907Y582877D01*
G01X1245731Y577314D02*
X1244626Y578921D01*
G01X1248450Y573359D02*
X1247345Y574966D01*
G01X1249739Y586872D02*
X1248634Y588479D01*
G01X1252459Y582917D02*
X1251354Y584524D01*
G01X1255179Y578962D02*
X1254074Y580569D01*
G01X1249739Y586872D02*
X1248634Y588479D01*
G01X1252459Y582917D02*
X1251354Y584524D01*
G01X1255179Y578962D02*
X1254074Y580569D01*
G01X1236150Y578164D02*
X1235045Y579771D01*
G01X1238868Y574208D02*
X1237764Y575815D01*
G01X1241587Y570252D02*
X1240482Y571859D01*
G01X1283189Y108864D02*
X1392359Y84662D01*
G01X1392485Y85812D02*
X1283636Y109943D01*
G01X1392485Y85812D02*
X1283636Y109943D01*
G01X1283189Y108864D02*
X1392359Y84662D01*
G01X1306650Y263620D02*
X1405704Y200514D01*
G01X1306650Y263620D02*
X1405704Y200514D01*
G01X1408825Y209151D02*
X1328178Y261524D01*
G01X1408825Y209151D02*
X1328178Y261524D01*
G01X1302602Y266199D02*
X1304246Y265151D01*
G01X1298554Y268778D02*
X1300198Y267730D01*
G01X1302602Y266199D02*
X1304246Y265151D01*
G01X1298554Y268778D02*
X1300198Y267730D01*
G01X1317535Y268435D02*
X1315899Y269497D01*
G01X1321627Y265777D02*
X1319992Y266839D01*
G01X1325720Y263120D02*
X1324085Y264182D01*
G01X1317535Y268435D02*
X1315899Y269497D01*
G01X1321627Y265777D02*
X1319992Y266839D01*
G01X1325720Y263120D02*
X1324085Y264182D01*
G01X1313627Y453314D02*
X1312522Y454921D01*
G01X1316392Y449292D02*
X1315287Y450899D01*
G01X1456518Y245456D02*
X1318051Y446878D01*
G01X1313627Y453314D02*
X1312522Y454921D01*
G01X1316392Y449292D02*
X1315287Y450899D01*
G01X1456518Y245456D02*
X1318051Y446878D01*
G01X1321777Y453558D02*
X1320672Y455165D01*
G01X1324495Y449602D02*
X1323391Y451209D01*
G01X1345639Y418832D02*
X1326109Y447253D01*
G01X1321777Y453558D02*
X1320672Y455165D01*
G01X1324495Y449602D02*
X1323391Y451209D01*
G01X1345639Y418832D02*
X1326109Y447253D01*
G01X1316340Y461470D02*
X1287321Y503699D01*
G01X1319058Y457514D02*
X1317954Y459121D01*
G01X1323502Y464168D02*
X1293752Y507449D01*
G01X1326266Y460146D02*
X1325162Y461753D01*
G01X1329030Y456124D02*
X1327926Y457731D01*
G01X1323502Y464168D02*
X1293752Y507449D01*
G01X1326266Y460146D02*
X1325162Y461753D01*
G01X1329030Y456124D02*
X1327926Y457731D01*
G01X1330251Y469809D02*
X1300720Y512747D01*
G01X1330251Y469809D02*
X1300720Y512747D01*
G01X1316340Y461470D02*
X1287321Y503699D01*
G01X1319058Y457514D02*
X1317954Y459121D01*
G01X1282988Y510004D02*
X1281884Y511611D01*
G01X1285707Y506048D02*
X1284602Y507655D01*
G01X1286699Y517709D02*
X1285595Y519316D01*
G01X1289418Y513753D02*
X1288314Y515360D01*
G01X1292137Y509798D02*
X1291033Y511405D01*
G01X1286699Y517709D02*
X1285595Y519316D01*
G01X1289418Y513753D02*
X1288314Y515360D01*
G01X1292137Y509798D02*
X1291033Y511405D01*
G01X1293665Y523005D02*
X1292560Y524612D01*
G01X1296385Y519050D02*
X1295280Y520657D01*
G01X1299105Y515095D02*
X1298000Y516702D01*
G01X1293665Y523005D02*
X1292560Y524612D01*
G01X1296385Y519050D02*
X1295280Y520657D01*
G01X1299105Y515095D02*
X1298000Y516702D01*
G01X1282988Y510004D02*
X1281884Y511611D01*
G01X1285707Y506048D02*
X1284602Y507655D01*
G01X1345076Y180196D02*
X1414859Y135797D01*
G01X1345615Y181217D02*
X1415692Y136631D01*
G01X1345615Y181217D02*
X1415692Y136631D01*
G01X1345076Y180196D02*
X1414859Y135797D01*
G01X1369357Y157230D02*
X1410323Y131144D01*
G01X1369974Y158201D02*
X1411156Y131977D01*
G01X1369752Y158342D02*
X1369974Y158201D01*
G01X1369212Y157322D02*
X1369357Y157230D01*
G01X1369974Y158201D02*
X1411156Y131977D01*
G01X1369752Y158342D02*
X1369974Y158201D01*
G01X1369211Y157322D02*
X1369212D01*
G01X1369752Y158342D02*
X1369974Y158201D01*
G01D02*
X1411156Y131977D01*
G01X1369357Y157230D02*
X1410323Y131144D01*
G01X1369212Y157322D02*
X1369357Y157230D01*
G01X1369752Y158342D02*
X1369974Y158201D01*
G01X1369357Y157230D02*
X1410323Y131144D01*
G01X1369212Y157322D02*
X1369357Y157230D01*
G01X1369211Y157322D02*
X1369212D01*
G01X1369211D02*
X1369212D01*
G01X1366580Y151464D02*
X1405186Y126868D01*
G01X1367119Y152485D02*
X1406020Y127701D01*
G01X1367119Y152485D02*
X1406020Y127701D01*
G01X1366580Y151464D02*
X1405186Y126868D01*
G01X1374565Y203319D02*
X1389849Y179326D01*
G01X1375398Y204152D02*
X1390697Y180137D01*
G01X1367804Y207626D02*
X1374565Y203319D01*
G01X1363688Y210248D02*
X1365332Y209200D01*
G01X1359572Y212870D02*
X1361217Y211822D01*
G01X1375398Y204152D02*
X1390697Y180137D01*
G01X1374565Y203319D02*
X1389849Y179326D01*
G01X1367804Y207626D02*
X1374565Y203319D01*
G01X1363688Y210248D02*
X1365332Y209200D01*
G01X1359572Y212870D02*
X1361217Y211822D01*
G01X1371444Y175092D02*
X1387847Y171455D01*
G01X1371833Y176184D02*
X1388294Y172534D01*
G01X1371833Y176184D02*
X1388294Y172534D01*
G01X1371444Y175092D02*
X1387847Y171455D01*
G01X1355456Y215492D02*
X1357101Y214444D01*
G01X1355456Y215492D02*
X1357101Y214444D01*
G01X1461066Y250861D02*
X1352826Y408374D01*
G01X1464429Y259136D02*
X1330690Y453710D01*
G01X1464429Y259136D02*
X1330690Y453710D01*
G01X1502539Y219310D02*
X1337442Y459354D01*
G01X1502539Y219310D02*
X1337442Y459354D01*
G01X1461066Y250861D02*
X1352826Y408374D01*
G01X1348403Y414810D02*
X1347298Y416417D01*
G01X1351167Y410788D02*
X1350062Y412396D01*
G01X1348403Y414810D02*
X1347298Y416417D01*
G01X1351167Y410788D02*
X1350062Y412396D01*
G01X1333017Y465789D02*
X1331912Y467395D01*
G01X1335782Y461768D02*
X1334677Y463374D01*
G01X1333017Y465789D02*
X1331912Y467395D01*
G01X1335782Y461768D02*
X1334677Y463374D01*
G01X1425094Y84662D02*
X1425920D01*
G01X1425094Y85812D02*
X1425920D01*
G01X1422457Y87299D02*
G03X1425094Y84662I2637J0D01*
G01X1423607Y87299D02*
G03X1425094Y85812I1487J0D01*
G01X1422457Y123872D02*
Y87299D01*
G01X1423607Y124208D02*
Y87299D01*
G01X1425094Y85812D02*
X1425920D01*
G01X1425094Y84662D02*
X1425920D01*
G01X1423607Y87299D02*
G03X1425094Y85812I1487J0D01*
G01X1422457Y87299D02*
G03X1425094Y84662I2637J0D01*
G01X1423607Y124208D02*
Y87299D01*
G01X1422457Y123872D02*
Y87299D01*
G01X1418007Y88599D02*
X1418833D01*
G01X1418007Y89749D02*
X1418833D01*
G01X1415370Y91236D02*
G03X1418007Y88599I2637J0D01*
G01X1416520Y91236D02*
G03X1418007Y89749I1487J0D01*
G01X1415370Y123221D02*
Y91236D01*
G01X1416520Y123557D02*
Y91236D01*
G01X1418007Y89749D02*
X1418833D01*
G01X1418007Y88599D02*
X1418833D01*
G01X1416520Y91236D02*
G03X1418007Y89749I1487J0D01*
G01X1415370Y91236D02*
G03X1418007Y88599I2637J0D01*
G01X1416520Y123557D02*
Y91236D01*
G01X1415370Y123221D02*
Y91236D01*
G01X1410921Y84662D02*
X1411747D01*
G01X1410921Y85812D02*
X1411747D01*
G01X1408284Y87299D02*
G03X1410921Y84662I2637J0D01*
G01X1409434Y87299D02*
G03X1410921Y85812I1487J0D01*
G01X1408284Y121993D02*
Y87299D01*
G01X1409434Y122328D02*
Y87299D01*
G01X1410921Y85812D02*
X1411747D01*
G01X1410921Y84662D02*
X1411747D01*
G01X1409434Y87299D02*
G03X1410921Y85812I1487J0D01*
G01X1408284Y87299D02*
G03X1410921Y84662I2637J0D01*
G01X1409434Y122328D02*
Y87299D01*
G01X1408284Y121993D02*
Y87299D01*
G01X1403834Y88599D02*
X1404660D01*
G01X1403834Y89749D02*
X1404660D01*
G01X1401197Y91236D02*
G03X1403834Y88599I2637J0D01*
G01X1402347Y91236D02*
G03X1403834Y89749I1487J0D01*
G01X1401197Y121504D02*
Y91236D01*
G01X1402347Y121888D02*
Y91236D01*
G01X1403834Y89749D02*
X1404660D01*
G01X1403834Y88599D02*
X1404660D01*
G01X1402347Y91236D02*
G03X1403834Y89749I1487J0D01*
G01X1401197Y91236D02*
G03X1403834Y88599I2637J0D01*
G01X1402347Y121888D02*
Y91236D01*
G01X1401197Y121504D02*
Y91236D01*
G01X1392359Y84662D02*
X1397573D01*
G01Y85812D02*
X1392485D01*
G01X1397573D02*
X1392485D01*
G01X1392359Y84662D02*
X1397573D01*
G01X1423422Y163429D02*
X1443717Y131583D01*
G01X1424270Y164240D02*
X1444867Y131919D01*
G01X1395228Y183208D02*
X1423422Y163429D01*
G01X1396076Y184019D02*
X1424270Y164240D01*
G01D02*
X1444867Y131919D01*
G01X1423422Y163429D02*
X1443717Y131583D01*
G01X1396076Y184019D02*
X1424270Y164240D01*
G01X1395228Y183208D02*
X1423422Y163429D01*
G01X1418599Y159153D02*
X1436630Y126744D01*
G01X1419476Y159943D02*
X1437780Y127043D01*
G01X1389849Y179326D02*
X1418599Y159153D01*
G01X1390697Y180137D02*
X1419476Y159943D01*
G01D02*
X1437780Y127043D01*
G01X1418599Y159153D02*
X1436630Y126744D01*
G01X1390697Y180137D02*
X1419476Y159943D01*
G01X1389849Y179326D02*
X1418599Y159153D01*
G01X1413771Y154940D02*
X1429543Y126589D01*
G01X1414635Y155754D02*
X1430693Y126888D01*
G01X1387847Y171455D02*
X1413771Y154940D01*
G01X1388294Y172534D02*
X1414635Y155754D01*
G01D02*
X1430693Y126888D01*
G01X1413771Y154940D02*
X1429543Y126589D01*
G01X1388294Y172534D02*
X1414635Y155754D01*
G01X1387847Y171455D02*
X1413771Y154940D01*
G01X1414859Y135797D02*
X1422457Y123872D01*
G01X1415692Y136631D02*
X1423607Y124208D01*
G01X1415692Y136631D02*
X1423607Y124208D01*
G01X1414859Y135797D02*
X1422457Y123872D01*
G01X1410323Y131144D02*
X1415370Y123221D01*
G01X1411156Y131977D02*
X1416520Y123557D01*
G01X1411156Y131977D02*
X1416520Y123557D01*
G01X1410323Y131144D02*
X1415370Y123221D01*
G01X1405186Y126868D02*
X1408284Y121993D01*
G01X1406020Y127701D02*
X1409434Y122328D01*
G01X1406020Y127701D02*
X1409434Y122328D01*
G01X1405186Y126868D02*
X1408284Y121993D01*
G01X1400287Y122718D02*
X1401197Y121504D01*
G01X1401011Y123670D02*
X1402347Y121888D01*
G01X1401011Y123670D02*
X1402347Y121888D01*
G01X1400287Y122718D02*
X1401197Y121504D01*
G01X1379718Y207554D02*
X1395228Y183208D01*
G01X1380551Y208387D02*
X1396076Y184019D01*
G01X1380551Y208387D02*
X1396076Y184019D01*
G01X1379718Y207554D02*
X1395228Y183208D01*
G01X1424433Y173282D02*
X1477192Y139667D01*
G01X1423600Y172449D02*
X1476359Y138834D01*
G01X1406537Y201347D02*
X1424433Y173282D01*
G01X1405704Y200514D02*
X1423600Y172449D01*
G01D02*
X1476359Y138834D01*
G01X1424433Y173282D02*
X1477192Y139667D01*
G01X1405704Y200514D02*
X1423600Y172449D01*
G01X1406537Y201347D02*
X1424433Y173282D01*
G01X1409654Y209985D02*
X1431375Y176989D01*
G01X1430545Y176156D02*
X1408825Y209151D01*
G01X1430545Y176156D02*
X1408825Y209151D01*
G01X1409654Y209985D02*
X1431375Y176989D01*
G01X1445648Y88599D02*
X1447180D01*
G01X1445648Y89749D02*
X1447180D01*
G01X1443717Y90530D02*
G03X1445648Y88599I1931J0D01*
G01X1444867Y90530D02*
G03X1445648Y89749I781J0D01*
G01X1443717Y131583D02*
Y90530D01*
G01X1444867Y131919D02*
Y90530D01*
G01X1445648Y89749D02*
X1447180D01*
G01X1445648Y88599D02*
X1447180D01*
G01X1444867Y90530D02*
G03X1445648Y89749I781J0D01*
G01X1443717Y90530D02*
G03X1445648Y88599I1931J0D01*
G01X1444867Y131919D02*
Y90530D01*
G01X1443717Y131583D02*
Y90530D01*
G01X1438535Y84662D02*
X1440093D01*
G01X1438535Y85812D02*
X1440093D01*
G01X1436630Y86567D02*
G03X1438535Y84662I1905J0D01*
G01X1437780Y86567D02*
G03X1438535Y85812I755J0D01*
G01X1436630Y126744D02*
Y86567D01*
G01X1437780Y127043D02*
Y86567D01*
G01X1438535Y85812D02*
X1440093D01*
G01X1438535Y84662D02*
X1440093D01*
G01X1437780Y86567D02*
G03X1438535Y85812I755J0D01*
G01X1436630Y86567D02*
G03X1438535Y84662I1905J0D01*
G01X1437780Y127043D02*
Y86567D01*
G01X1436630Y126744D02*
Y86567D01*
G01X1432180Y88599D02*
X1433006D01*
G01X1432180Y89749D02*
X1433006D01*
G01X1429543Y91236D02*
G03X1432180Y88599I2637J0D01*
G01X1430693Y91236D02*
G03X1432180Y89749I1487J0D01*
G01X1429543Y126589D02*
Y91236D01*
G01X1430693Y126888D02*
Y91236D01*
G01X1432180Y89749D02*
X1433006D01*
G01X1432180Y88599D02*
X1433006D01*
G01X1430693Y91236D02*
G03X1432180Y89749I1487J0D01*
G01X1429543Y91236D02*
G03X1432180Y88599I2637J0D01*
G01X1430693Y126888D02*
Y91236D01*
G01X1429543Y126589D02*
Y91236D01*
G01X1431374Y176989D02*
X1482282Y143837D01*
G01X1481445Y143009D02*
X1430545Y176156D01*
G01X1481445Y143009D02*
X1430545Y176156D01*
G01X1481445Y143009D02*
X1430545Y176156D01*
G01X1431374Y176989D02*
X1482282Y143837D01*
G01X1487031Y174101D02*
X1456518Y245456D01*
G01X1488043Y174660D02*
X1457531Y246014D01*
G01X1488043Y174660D02*
X1457531Y246014D01*
G01X1487031Y174101D02*
X1456518Y245456D01*
G01X1431375Y176989D02*
X1431374D01*
G01X1431375D02*
X1431374D01*
G01X1501559Y125170D02*
X1466004Y180935D01*
G01X1500409Y124834D02*
X1465157Y180124D01*
G01X1500409Y124834D02*
X1465157Y180124D01*
G01X1501559Y125170D02*
X1466004Y180935D01*
G01X1467793Y189972D02*
X1508646Y125897D01*
G01X1507496Y125561D02*
X1466946Y189161D01*
G01X1507496Y125561D02*
X1466946Y189161D01*
G01X1467793Y189972D02*
X1508646Y125897D01*
G01X1492578Y177156D02*
X1461066Y250861D01*
G01X1493590Y177715D02*
X1462079Y251419D01*
G01X1499464Y180149D02*
X1465442Y259694D01*
G01X1498452Y179590D02*
X1464429Y259136D01*
G01X1498452Y179590D02*
X1464429Y259136D01*
G01X1499464Y180149D02*
X1465442Y259694D01*
G01X1493590Y177715D02*
X1462079Y251419D01*
G01X1492578Y177156D02*
X1461066Y250861D01*
G01X1514582Y86596D02*
Y134304D01*
G01X1515732Y86596D02*
Y134664D01*
G01X1513798Y85812D02*
G03X1514582Y86596I0J784D01*
G01X1513798Y84662D02*
G03X1515732Y86596I0J1934D01*
G01X1512269Y85812D02*
X1513798D01*
G01X1512269Y84662D02*
X1513798D01*
G01X1515732Y86596D02*
Y134664D01*
G01X1514582Y86596D02*
Y134304D01*
G01X1513798Y84662D02*
G03X1515732Y86596I0J1934D01*
G01X1513798Y85812D02*
G03X1514582Y86596I0J784D01*
G01X1512269Y84662D02*
X1513798D01*
G01X1512269Y85812D02*
X1513798D01*
G01X1521669Y90604D02*
Y135134D01*
G01X1522819Y90604D02*
Y135494D01*
G01X1520814Y89749D02*
G03X1521669Y90604I0J855D01*
G01X1520814Y88599D02*
G03X1522819Y90604I0J2005D01*
G01X1519356Y89749D02*
X1520814D01*
G01X1519356Y88599D02*
X1520814D01*
G01X1522819Y90604D02*
Y135494D01*
G01X1521669Y90604D02*
Y135134D01*
G01X1520814Y88599D02*
G03X1522819Y90604I0J2005D01*
G01X1520814Y89749D02*
G03X1521669Y90604I0J855D01*
G01X1519356Y88599D02*
X1520814D01*
G01X1519356Y89749D02*
X1520814D01*
G01X1485417Y84662D02*
X1483923D01*
G01X1485417Y85812D02*
X1483923D01*
G01X1487386Y86631D02*
G02X1485417Y84662I-1969J0D01*
G01X1486236Y86631D02*
G02X1485417Y85812I-819J0D01*
G01X1487386Y123678D02*
Y86631D01*
G01X1486236Y123342D02*
Y86631D01*
G01X1485417Y85812D02*
X1483923D01*
G01X1485417Y84662D02*
X1483923D01*
G01X1486236Y86631D02*
G02X1485417Y85812I-819J0D01*
G01X1487386Y86631D02*
G02X1485417Y84662I-1969J0D01*
G01X1486236Y123342D02*
Y86631D01*
G01X1487386Y123678D02*
Y86631D01*
G01X1492516Y88599D02*
X1491009D01*
G01Y89749D02*
X1492516D01*
G01X1494472Y90555D02*
G02X1492516Y88599I-1956J0D01*
G01Y89749D02*
G03X1493322Y90555I0J806D01*
G01X1494472Y124678D02*
Y90555D01*
G01X1493322D02*
Y124343D01*
G01Y90555D02*
Y124343D01*
G01X1494472Y124678D02*
Y90555D01*
G01X1492516Y89749D02*
G03X1493322Y90555I0J806D01*
G01X1494472D02*
G02X1492516Y88599I-1956J0D01*
G01X1491009Y89749D02*
X1492516D01*
G01Y88599D02*
X1491009D01*
G01X1501559Y86642D02*
Y125170D01*
G01X1500409Y86642D02*
Y124834D01*
G01X1499579Y84662D02*
G03X1501559Y86642I0J1980D01*
G01X1499579Y85812D02*
G03X1500409Y86642I0J830D01*
G01X1498096Y84662D02*
X1499579D01*
G01X1498096Y85812D02*
X1499579D01*
G01X1500409Y86642D02*
Y124834D01*
G01X1501559Y86642D02*
Y125170D01*
G01X1499579Y85812D02*
G03X1500409Y86642I0J830D01*
G01X1499579Y84662D02*
G03X1501559Y86642I0J1980D01*
G01X1498096Y85812D02*
X1499579D01*
G01X1498096Y84662D02*
X1499579D01*
G01X1506681Y88599D02*
X1505183D01*
G01Y89749D02*
X1506681D01*
G01X1508646Y90564D02*
G02X1506681Y88599I-1965J0D01*
G01Y89749D02*
G03X1507496Y90564I0J815D01*
G01X1508646Y125897D02*
Y90564D01*
G01X1507496D02*
Y125561D01*
G01Y90564D02*
Y125561D01*
G01X1508646Y125897D02*
Y90564D01*
G01X1506681Y89749D02*
G03X1507496Y90564I0J815D01*
G01X1508646D02*
G02X1506681Y88599I-1965J0D01*
G01X1505183Y89749D02*
X1506681D01*
G01Y88599D02*
X1505183D01*
G01X1514582Y134304D02*
X1487031Y174101D01*
G01X1515732Y134664D02*
X1488043Y174660D01*
G01X1515732Y134664D02*
X1488043Y174660D01*
G01X1514582Y134304D02*
X1487031Y174101D01*
G01X1521669Y135134D02*
X1492578Y177156D01*
G01X1522819Y135494D02*
X1493590Y177715D01*
G01X1529905Y136203D02*
X1499464Y180149D01*
G01X1517203Y152519D02*
X1498452Y179590D01*
G01X1528755Y135843D02*
X1517203Y152519D01*
G01D02*
X1498452Y179590D01*
G01X1529905Y136203D02*
X1499464Y180149D01*
G01X1528755Y135843D02*
X1517203Y152519D01*
G01X1529905Y136203D02*
X1499464Y180149D01*
G01X1522819Y135494D02*
X1493590Y177715D01*
G01X1521669Y135134D02*
X1492578Y177156D01*
G01X1477192Y139667D02*
X1487386Y123678D01*
G01X1476359Y138834D02*
X1486236Y123342D01*
G01X1476359Y138834D02*
X1486236Y123342D01*
G01X1477192Y139667D02*
X1487386Y123678D01*
G01X1482282Y143837D02*
X1494472Y124678D01*
G01X1493321Y124343D02*
X1481445Y143009D01*
G01X1493321Y124343D02*
X1481445Y143009D01*
G01X1482282Y143837D02*
X1494472Y124678D01*
G01X1521062Y178939D02*
X1503552Y219868D01*
G01X1520045Y178390D02*
X1502539Y219310D01*
G01X1536114Y156206D02*
X1521062Y178939D01*
G01X1535031Y155757D02*
X1520045Y178390D01*
G01D02*
X1502539Y219310D01*
G01X1521062Y178939D02*
X1503552Y219868D01*
G01X1535031Y155757D02*
X1520045Y178390D01*
G01X1536114Y156206D02*
X1521062Y178939D01*
G01X1529905Y86699D02*
Y136203D01*
G01X1528755Y86699D02*
Y135843D01*
G01X1527868Y84662D02*
G03X1529905Y86699I0J2037D01*
G01X1527868Y85812D02*
G03X1528755Y86699I0J887D01*
G01X1526442Y84662D02*
X1527868D01*
G01X1526442Y85812D02*
X1527868D01*
G01X1528755Y86699D02*
Y135843D01*
G01X1529905Y86699D02*
Y136203D01*
G01X1527868Y85812D02*
G03X1528755Y86699I0J887D01*
G01X1527868Y84662D02*
G03X1529905Y86699I0J2037D01*
G01X1526442Y85812D02*
X1527868D01*
G01X1526442Y84662D02*
X1527868D01*
G01X1536993Y90644D02*
Y151878D01*
G01X1535843Y90644D02*
Y151762D01*
G01X1534948Y88599D02*
G03X1536993Y90644I0J2045D01*
G01X1534948Y89749D02*
G03X1535843Y90644I0J895D01*
G01X1533529Y88599D02*
X1534948D01*
G01X1533529Y89749D02*
X1534948D01*
G01X1535843Y90644D02*
Y151762D01*
G01X1536993Y90644D02*
Y151878D01*
G01X1534948Y89749D02*
G03X1535843Y90644I0J895D01*
G01X1534948Y88599D02*
G03X1536993Y90644I0J2045D01*
G01X1533529Y89749D02*
X1534948D01*
G01X1533529Y88599D02*
X1534948D01*
G01X1536993Y151878D02*
X1536114Y156206D01*
G01X1535843Y151762D02*
X1535031Y155757D01*
G01X1535843Y151762D02*
X1535031Y155757D01*
G01X1536993Y151878D02*
X1536114Y156206D01*
M02*
